(lib_symbols
	(symbol "antmicroCapacitors0402:C_10n_0402"
			(pin_numbers
				(hide yes)
			)
			(pin_names
				(hide yes)
			)
			(exclude_from_sim no)
			(in_bom yes)
			(on_board yes)
			(property "Reference" "C"
				(at 20.32 -5.08 0)
				(effects
					(font
						(size 1.27 1.27)
						(thickness 0.15)
					)
					(justify left bottom)
				)
			)
			(property "Value" "C_10n_0402"
				(at 20.32 -10.16 0)
				(effects
					(font
						(size 1.27 1.27)
						(thickness 0.15)
					)
					(justify left bottom)
					(hide yes)
				)
			)
			(property "Footprint" "antmicro-footprints:C_0402_1005Metric"
				(at 20.32 -12.7 0)
				(effects
					(font
						(size 1.27 1.27)
						(thickness 0.15)
					)
					(justify left bottom)
					(hide yes)
				)
			)
			(property "Datasheet" "https://www.murata.com/products/productdetail?partno=GRM155R71H103KA88%23"
				(at 20.32 -15.24 0)
				(effects
					(font
						(size 1.27 1.27)
						(thickness 0.15)
					)
					(justify left bottom)
					(hide yes)
				)
			)
			(property "Description" "SMD Multilayer Ceramic Capacitor, 10000 pF, 50 V, 0402 [1005 Metric], ± 10%, X7R, GRM Series"
				(at 0 0 0)
				(effects
					(font
						(size 1.27 1.27)
					)
					(hide yes)
				)
			)
			(property "MPN" "GRM155R71H103KA88D"
				(at 20.32 -17.78 0)
				(effects
					(font
						(size 1.27 1.27)
						(thickness 0.15)
					)
					(justify left bottom)
					(hide yes)
				)
			)
			(property "Manufacturer" "Murata"
				(at 20.32 -20.32 0)
				(effects
					(font
						(size 1.27 1.27)
						(thickness 0.15)
					)
					(justify left bottom)
					(hide yes)
				)
			)
			(property "License" "Apache-2.0"
				(at 20.32 -22.86 0)
				(effects
					(font
						(size 1.27 1.27)
						(thickness 0.15)
					)
					(justify left bottom)
					(hide yes)
				)
			)
			(property "Author" "Antmicro"
				(at 20.32 -25.4 0)
				(effects
					(font
						(size 1.27 1.27)
						(thickness 0.15)
					)
					(justify left bottom)
					(hide yes)
				)
			)
			(property "Val" "10n"
				(at 20.32 -7.62 0)
				(effects
					(font
						(size 1.27 1.27)
						(thickness 0.15)
					)
					(justify left bottom)
				)
			)
			(property "Voltage" "50V"
				(at 20.32 -27.94 0)
				(effects
					(font
						(size 1.27 1.27)
					)
					(justify left bottom)
					(hide yes)
				)
			)
			(property "Dielectric" "X7R"
				(at 20.32 -30.48 0)
				(effects
					(font
						(size 1.27 1.27)
					)
					(justify left bottom)
					(hide yes)
				)
			)
			(property "ki_keywords" "0402, SMT, CAPACITOR, PASSIVE"
				(at 0 0 0)
				(effects
					(font
						(size 1.27 1.27)
					)
					(hide yes)
				)
			)
			(symbol "C_10n_0402_0_1"
				(polyline
					(pts
						(xy 2.032 -1.524) (xy 2.032 1.524)
					)
					(stroke
						(width 0.3048)
						(type default)
					)
					(fill
						(type none)
					)
				)
				(polyline
					(pts
						(xy 3.048 -1.524) (xy 3.048 1.524)
					)
					(stroke
						(width 0.3302)
						(type default)
					)
					(fill
						(type none)
					)
				)
			)
			(symbol "C_10n_0402_1_1"
				(pin passive line
					(at 0 0 0)
					(length 2.032)
					(name "~"
						(effects
							(font
								(size 1.27 1.27)
							)
						)
					)
					(number "1"
						(effects
							(font
								(size 1.27 1.27)
							)
						)
					)
				)
				(pin passive line
					(at 5.08 0 180)
					(length 2.032)
					(name "~"
						(effects
							(font
								(size 1.27 1.27)
							)
						)
					)
					(number "2"
						(effects
							(font
								(size 1.27 1.27)
							)
						)
					)
				)
			)
		)
	(symbol "antmicroCapacitors0402:C_1u_0402"
			(pin_numbers
				(hide yes)
			)
			(pin_names
				(hide yes)
			)
			(exclude_from_sim no)
			(in_bom yes)
			(on_board yes)
			(property "Reference" "C"
				(at 20.32 -5.08 0)
				(effects
					(font
						(size 1.27 1.27)
						(thickness 0.15)
					)
					(justify left bottom)
				)
			)
			(property "Value" "C_1u_0402"
				(at 20.32 -10.16 0)
				(effects
					(font
						(size 1.27 1.27)
						(thickness 0.15)
					)
					(justify left bottom)
					(hide yes)
				)
			)
			(property "Footprint" "antmicro-footprints:C_0402_1005Metric"
				(at 20.32 -12.7 0)
				(effects
					(font
						(size 1.27 1.27)
						(thickness 0.15)
					)
					(justify left bottom)
					(hide yes)
				)
			)
			(property "Datasheet" "https://product.tdk.com/en/search/capacitor/ceramic/mlcc/info?part_no=C1005X6S1A105K050BC"
				(at 20.32 -15.24 0)
				(effects
					(font
						(size 1.27 1.27)
						(thickness 0.15)
					)
					(justify left bottom)
					(hide yes)
				)
			)
			(property "Description" "SMD Multilayer Ceramic Capacitor, 1 µF, 10 V, 0402 [1005 Metric], ± 10%, X6S, C"
				(at 0 0 0)
				(effects
					(font
						(size 1.27 1.27)
					)
					(hide yes)
				)
			)
			(property "MPN" "C1005X6S1A105K050BC"
				(at 20.32 -17.78 0)
				(effects
					(font
						(size 1.27 1.27)
						(thickness 0.15)
					)
					(justify left bottom)
					(hide yes)
				)
			)
			(property "Manufacturer" "TDK"
				(at 20.32 -20.32 0)
				(effects
					(font
						(size 1.27 1.27)
						(thickness 0.15)
					)
					(justify left bottom)
					(hide yes)
				)
			)
			(property "License" "Apache-2.0"
				(at 20.32 -22.86 0)
				(effects
					(font
						(size 1.27 1.27)
						(thickness 0.15)
					)
					(justify left bottom)
					(hide yes)
				)
			)
			(property "Author" "Antmicro"
				(at 20.32 -25.4 0)
				(effects
					(font
						(size 1.27 1.27)
						(thickness 0.15)
					)
					(justify left bottom)
					(hide yes)
				)
			)
			(property "Val" "1u"
				(at 20.32 -7.62 0)
				(effects
					(font
						(size 1.27 1.27)
						(thickness 0.15)
					)
					(justify left bottom)
				)
			)
			(property "Voltage" ""
				(at 20.32 -27.94 0)
				(effects
					(font
						(size 1.27 1.27)
					)
					(justify left bottom)
					(hide yes)
				)
			)
			(property "Dielectric" ""
				(at 20.32 -30.48 0)
				(effects
					(font
						(size 1.27 1.27)
					)
					(justify left bottom)
					(hide yes)
				)
			)
			(property "ki_keywords" "0402, SMT, CAPACITOR, PASSIVE, CERAMIC, MLCC"
				(at 0 0 0)
				(effects
					(font
						(size 1.27 1.27)
					)
					(hide yes)
				)
			)
			(symbol "C_1u_0402_0_1"
				(polyline
					(pts
						(xy 2.032 -1.524) (xy 2.032 1.524)
					)
					(stroke
						(width 0.3048)
						(type default)
					)
					(fill
						(type none)
					)
				)
				(polyline
					(pts
						(xy 3.048 -1.524) (xy 3.048 1.524)
					)
					(stroke
						(width 0.3302)
						(type default)
					)
					(fill
						(type none)
					)
				)
			)
			(symbol "C_1u_0402_1_1"
				(pin passive line
					(at 0 0 0)
					(length 2.032)
					(name "~"
						(effects
							(font
								(size 1.27 1.27)
							)
						)
					)
					(number "1"
						(effects
							(font
								(size 1.27 1.27)
							)
						)
					)
				)
				(pin passive line
					(at 5.08 0 180)
					(length 2.032)
					(name "~"
						(effects
							(font
								(size 1.27 1.27)
							)
						)
					)
					(number "2"
						(effects
							(font
								(size 1.27 1.27)
							)
						)
					)
				)
			)
		)
	(symbol "antmicroCapacitors0402:C_4u7_0402"
			(pin_numbers
				(hide yes)
			)
			(pin_names
				(hide yes)
			)
			(exclude_from_sim no)
			(in_bom yes)
			(on_board yes)
			(property "Reference" "C"
				(at 20.32 -5.08 0)
				(effects
					(font
						(size 1.27 1.27)
						(thickness 0.15)
					)
					(justify left bottom)
				)
			)
			(property "Value" "C_4u7_0402"
				(at 20.32 -10.16 0)
				(effects
					(font
						(size 1.27 1.27)
						(thickness 0.15)
					)
					(justify left bottom)
					(hide yes)
				)
			)
			(property "Footprint" "antmicro-footprints:C_0402_1005Metric"
				(at 20.32 -12.7 0)
				(effects
					(font
						(size 1.27 1.27)
						(thickness 0.15)
					)
					(justify left bottom)
					(hide yes)
				)
			)
			(property "Datasheet" "https://www.murata.com/products/productdetail?partno=GRM155R61A475MEAA%23"
				(at 20.32 -15.24 0)
				(effects
					(font
						(size 1.27 1.27)
						(thickness 0.15)
					)
					(justify left bottom)
					(hide yes)
				)
			)
			(property "Description" "SMD Multilayer Ceramic Capacitor, 4.7 µF, 10 V, 0402 [1005 Metric], ± 20%, X5R, GRM Series"
				(at 0 0 0)
				(effects
					(font
						(size 1.27 1.27)
					)
					(hide yes)
				)
			)
			(property "MPN" "GRM155R61A475MEAAD"
				(at 20.32 -17.78 0)
				(effects
					(font
						(size 1.27 1.27)
						(thickness 0.15)
					)
					(justify left bottom)
					(hide yes)
				)
			)
			(property "Manufacturer" "Murata"
				(at 20.32 -20.32 0)
				(effects
					(font
						(size 1.27 1.27)
						(thickness 0.15)
					)
					(justify left bottom)
					(hide yes)
				)
			)
			(property "License" "Apache-2.0"
				(at 20.32 -22.86 0)
				(effects
					(font
						(size 1.27 1.27)
						(thickness 0.15)
					)
					(justify left bottom)
					(hide yes)
				)
			)
			(property "Author" "Antmicro"
				(at 20.32 -25.4 0)
				(effects
					(font
						(size 1.27 1.27)
						(thickness 0.15)
					)
					(justify left bottom)
					(hide yes)
				)
			)
			(property "Val" "4u7"
				(at 20.32 -7.62 0)
				(effects
					(font
						(size 1.27 1.27)
						(thickness 0.15)
					)
					(justify left bottom)
				)
			)
			(property "Voltage" ""
				(at 20.32 -27.94 0)
				(effects
					(font
						(size 1.27 1.27)
					)
					(justify left bottom)
					(hide yes)
				)
			)
			(property "Dielectric" ""
				(at 20.32 -30.48 0)
				(effects
					(font
						(size 1.27 1.27)
					)
					(justify left bottom)
					(hide yes)
				)
			)
			(property "ki_keywords" "0402, SMT, CAPACITOR, PASSIVE"
				(at 0 0 0)
				(effects
					(font
						(size 1.27 1.27)
					)
					(hide yes)
				)
			)
			(symbol "C_4u7_0402_0_1"
				(polyline
					(pts
						(xy 2.032 -1.524) (xy 2.032 1.524)
					)
					(stroke
						(width 0.3048)
						(type default)
					)
					(fill
						(type none)
					)
				)
				(polyline
					(pts
						(xy 3.048 -1.524) (xy 3.048 1.524)
					)
					(stroke
						(width 0.3302)
						(type default)
					)
					(fill
						(type none)
					)
				)
			)
			(symbol "C_4u7_0402_1_1"
				(pin passive line
					(at 0 0 0)
					(length 2.032)
					(name "~"
						(effects
							(font
								(size 1.27 1.27)
							)
						)
					)
					(number "1"
						(effects
							(font
								(size 1.27 1.27)
							)
						)
					)
				)
				(pin passive line
					(at 5.08 0 180)
					(length 2.032)
					(name "~"
						(effects
							(font
								(size 1.27 1.27)
							)
						)
					)
					(number "2"
						(effects
							(font
								(size 1.27 1.27)
							)
						)
					)
				)
			)
		)
	(symbol "antmicroCapacitors0603:C_22u_0603"
			(pin_numbers
				(hide yes)
			)
			(pin_names
				(hide yes)
			)
			(exclude_from_sim no)
			(in_bom yes)
			(on_board yes)
			(property "Reference" "C"
				(at 20.32 -5.08 0)
				(effects
					(font
						(size 1.27 1.27)
						(thickness 0.15)
					)
					(justify left bottom)
				)
			)
			(property "Value" "C_22u_0603"
				(at 20.32 -10.16 0)
				(effects
					(font
						(size 1.27 1.27)
						(thickness 0.15)
					)
					(justify left bottom)
					(hide yes)
				)
			)
			(property "Footprint" "antmicro-footprints:C_0603_1608Metric"
				(at 20.32 -12.7 0)
				(effects
					(font
						(size 1.27 1.27)
						(thickness 0.15)
					)
					(justify left bottom)
					(hide yes)
				)
			)
			(property "Datasheet" "https://www.murata.com/products/productdetail?partno=GRM188R60J226MEA0%23"
				(at 20.32 -15.24 0)
				(effects
					(font
						(size 1.27 1.27)
						(thickness 0.15)
					)
					(justify left bottom)
					(hide yes)
				)
			)
			(property "Description" "SMD Multilayer Ceramic Capacitor, 22 µF, 6.3 V, 0603 [1608 Metric], ± 20%, X5R, GRM Series"
				(at 0 0 0)
				(effects
					(font
						(size 1.27 1.27)
					)
					(hide yes)
				)
			)
			(property "MPN" "GRM188R60J226MEA0D"
				(at 20.32 -17.78 0)
				(effects
					(font
						(size 1.27 1.27)
						(thickness 0.15)
					)
					(justify left bottom)
					(hide yes)
				)
			)
			(property "Manufacturer" "Murata"
				(at 20.32 -20.32 0)
				(effects
					(font
						(size 1.27 1.27)
						(thickness 0.15)
					)
					(justify left bottom)
					(hide yes)
				)
			)
			(property "License" "Apache-2.0"
				(at 20.32 -22.86 0)
				(effects
					(font
						(size 1.27 1.27)
						(thickness 0.15)
					)
					(justify left bottom)
					(hide yes)
				)
			)
			(property "Author" "Antmicro"
				(at 20.32 -25.4 0)
				(effects
					(font
						(size 1.27 1.27)
						(thickness 0.15)
					)
					(justify left bottom)
					(hide yes)
				)
			)
			(property "Val" "22u"
				(at 20.32 -7.62 0)
				(effects
					(font
						(size 1.27 1.27)
						(thickness 0.15)
					)
					(justify left bottom)
				)
			)
			(property "Voltage" ""
				(at 20.32 -27.94 0)
				(effects
					(font
						(size 1.27 1.27)
					)
					(justify left bottom)
					(hide yes)
				)
			)
			(property "Dielectric" ""
				(at 20.32 -30.48 0)
				(effects
					(font
						(size 1.27 1.27)
					)
					(justify left bottom)
					(hide yes)
				)
			)
			(property "ki_keywords" "0603, SMT, CAPACITOR, PASSIVE, CERAMIC, MLCC"
				(at 0 0 0)
				(effects
					(font
						(size 1.27 1.27)
					)
					(hide yes)
				)
			)
			(symbol "C_22u_0603_0_1"
				(polyline
					(pts
						(xy 2.032 -1.524) (xy 2.032 1.524)
					)
					(stroke
						(width 0.3048)
						(type default)
					)
					(fill
						(type none)
					)
				)
				(polyline
					(pts
						(xy 3.048 -1.524) (xy 3.048 1.524)
					)
					(stroke
						(width 0.3302)
						(type default)
					)
					(fill
						(type none)
					)
				)
			)
			(symbol "C_22u_0603_1_1"
				(pin passive line
					(at 0 0 0)
					(length 2.032)
					(name "~"
						(effects
							(font
								(size 1.27 1.27)
							)
						)
					)
					(number "1"
						(effects
							(font
								(size 1.27 1.27)
							)
						)
					)
				)
				(pin passive line
					(at 5.08 0 180)
					(length 2.032)
					(name "~"
						(effects
							(font
								(size 1.27 1.27)
							)
						)
					)
					(number "2"
						(effects
							(font
								(size 1.27 1.27)
							)
						)
					)
				)
			)
		)
	(symbol "antmicroCapacitorsmisc:C_100n_0201"
			(pin_numbers
				(hide yes)
			)
			(pin_names
				(hide yes)
			)
			(exclude_from_sim no)
			(in_bom yes)
			(on_board yes)
			(property "Reference" "C"
				(at 20.32 -5.08 0)
				(effects
					(font
						(size 1.27 1.27)
						(thickness 0.15)
					)
					(justify left bottom)
				)
			)
			(property "Value" "C_100n_0201_34"
				(at 20.32 -10.16 0)
				(effects
					(font
						(size 1.27 1.27)
						(thickness 0.15)
					)
					(justify left bottom)
					(hide yes)
				)
			)
			(property "Footprint" "antmicro-footprints:C_0201"
				(at 20.32 -12.7 0)
				(effects
					(font
						(size 1.27 1.27)
						(thickness 0.15)
					)
					(justify left bottom)
					(hide yes)
				)
			)
			(property "Datasheet" ""
				(at 20.32 -15.24 0)
				(effects
					(font
						(size 1.27 1.27)
						(thickness 0.15)
					)
					(justify left bottom)
					(hide yes)
				)
			)
			(property "Description" ""
				(at 0 0 0)
				(effects
					(font
						(size 1.27 1.27)
					)
					(hide yes)
				)
			)
			(property "MPN" "CC0201KRX6S5BB104"
				(at 20.32 -17.78 0)
				(effects
					(font
						(size 1.27 1.27)
						(thickness 0.15)
					)
					(justify left bottom)
					(hide yes)
				)
			)
			(property "Manufacturer" "Yaego"
				(at 20.32 -20.32 0)
				(effects
					(font
						(size 1.27 1.27)
						(thickness 0.15)
					)
					(justify left bottom)
					(hide yes)
				)
			)
			(property "License" "Apache-2.0"
				(at 20.32 -22.86 0)
				(effects
					(font
						(size 1.27 1.27)
						(thickness 0.15)
					)
					(justify left bottom)
					(hide yes)
				)
			)
			(property "Author" "Antmicro"
				(at 20.32 -25.4 0)
				(effects
					(font
						(size 1.27 1.27)
						(thickness 0.15)
					)
					(justify left bottom)
					(hide yes)
				)
			)
			(property "Val" "100n"
				(at 20.32 -7.62 0)
				(effects
					(font
						(size 1.27 1.27)
						(thickness 0.15)
					)
					(justify left bottom)
				)
			)
			(property "Voltage" ""
				(at 20.32 -27.94 0)
				(effects
					(font
						(size 1.27 1.27)
					)
					(justify left bottom)
					(hide yes)
				)
			)
			(property "Dielectric" ""
				(at 20.32 -30.48 0)
				(effects
					(font
						(size 1.27 1.27)
					)
					(justify left bottom)
					(hide yes)
				)
			)
			(symbol "C_100n_0201_0_1"
				(polyline
					(pts
						(xy 2.032 -1.524) (xy 2.032 1.524)
					)
					(stroke
						(width 0.3048)
						(type default)
					)
					(fill
						(type none)
					)
				)
				(polyline
					(pts
						(xy 3.048 -1.524) (xy 3.048 1.524)
					)
					(stroke
						(width 0.3302)
						(type default)
					)
					(fill
						(type none)
					)
				)
			)
			(symbol "C_100n_0201_1_1"
				(pin passive line
					(at 0 0 0)
					(length 2.032)
					(name "~"
						(effects
							(font
								(size 1.27 1.27)
							)
						)
					)
					(number "1"
						(effects
							(font
								(size 1.27 1.27)
							)
						)
					)
				)
				(pin passive line
					(at 5.08 0 180)
					(length 2.032)
					(name "~"
						(effects
							(font
								(size 1.27 1.27)
							)
						)
					)
					(number "2"
						(effects
							(font
								(size 1.27 1.27)
							)
						)
					)
				)
			)
		)
	(symbol "antmicroCapacitorsmisc:C_22u_25V_0805"
			(pin_numbers
				(hide yes)
			)
			(pin_names
				(hide yes)
			)
			(exclude_from_sim no)
			(in_bom yes)
			(on_board yes)
			(property "Reference" "C"
				(at 20.32 -5.08 0)
				(effects
					(font
						(size 1.27 1.27)
						(thickness 0.15)
					)
					(justify left bottom)
				)
			)
			(property "Value" "C_22u_25V_0805"
				(at 20.32 -10.16 0)
				(effects
					(font
						(size 1.27 1.27)
						(thickness 0.15)
					)
					(justify left bottom)
					(hide yes)
				)
			)
			(property "Footprint" "antmicro-footprints:C_0805_2012Metric"
				(at 20.32 -12.7 0)
				(effects
					(font
						(size 1.27 1.27)
						(thickness 0.15)
					)
					(justify left bottom)
					(hide yes)
				)
			)
			(property "Datasheet" "https://product.samsungsem.com/mlcc/CL21A226MAYNNN.do"
				(at 20.32 -15.24 0)
				(effects
					(font
						(size 1.27 1.27)
						(thickness 0.15)
					)
					(justify left bottom)
					(hide yes)
				)
			)
			(property "Description" "SMT Multilayer Ceramic Capacitor, 22uF, +/-20%, 25V, X5R, 0805 [2012 Metric]"
				(at 0 0 0)
				(effects
					(font
						(size 1.27 1.27)
					)
					(hide yes)
				)
			)
			(property "MPN" "CL21A226MAYNNNE"
				(at 20.32 -17.78 0)
				(effects
					(font
						(size 1.27 1.27)
						(thickness 0.15)
					)
					(justify left bottom)
					(hide yes)
				)
			)
			(property "Manufacturer" "Samsung Electro-Mechanics"
				(at 20.32 -20.32 0)
				(effects
					(font
						(size 1.27 1.27)
						(thickness 0.15)
					)
					(justify left bottom)
					(hide yes)
				)
			)
			(property "License" "Apache-2.0"
				(at 20.32 -22.86 0)
				(effects
					(font
						(size 1.27 1.27)
						(thickness 0.15)
					)
					(justify left bottom)
					(hide yes)
				)
			)
			(property "Author" "Antmicro"
				(at 20.32 -25.4 0)
				(effects
					(font
						(size 1.27 1.27)
						(thickness 0.15)
					)
					(justify left bottom)
					(hide yes)
				)
			)
			(property "Val" "22u_25V"
				(at 20.32 -7.62 0)
				(effects
					(font
						(size 1.27 1.27)
						(thickness 0.15)
					)
					(justify left bottom)
				)
			)
			(property "Voltage" ""
				(at 20.32 -27.94 0)
				(effects
					(font
						(size 1.27 1.27)
					)
					(justify left bottom)
					(hide yes)
				)
			)
			(property "Dielectric" ""
				(at 20.32 -30.48 0)
				(effects
					(font
						(size 1.27 1.27)
					)
					(justify left bottom)
					(hide yes)
				)
			)
			(property "ki_keywords" "0805, SMT, CAPACITOR, PASSIVE"
				(at 0 0 0)
				(effects
					(font
						(size 1.27 1.27)
					)
					(hide yes)
				)
			)
			(symbol "C_22u_25V_0805_0_1"
				(polyline
					(pts
						(xy 2.032 -1.524) (xy 2.032 1.524)
					)
					(stroke
						(width 0.3048)
						(type default)
					)
					(fill
						(type none)
					)
				)
				(polyline
					(pts
						(xy 3.048 -1.524) (xy 3.048 1.524)
					)
					(stroke
						(width 0.3302)
						(type default)
					)
					(fill
						(type none)
					)
				)
			)
			(symbol "C_22u_25V_0805_1_1"
				(pin passive line
					(at 0 0 0)
					(length 2.032)
					(name "~"
						(effects
							(font
								(size 1.27 1.27)
							)
						)
					)
					(number "1"
						(effects
							(font
								(size 1.27 1.27)
							)
						)
					)
				)
				(pin passive line
					(at 5.08 0 180)
					(length 2.032)
					(name "~"
						(effects
							(font
								(size 1.27 1.27)
							)
						)
					)
					(number "2"
						(effects
							(font
								(size 1.27 1.27)
							)
						)
					)
				)
			)
		)
	(symbol "antmicroEdgeConnectors:PCB-Edge_SODIMM_2x131_LPDDR5_Testbed"
			(exclude_from_sim no)
			(in_bom no)
			(on_board yes)
			(property "Reference" "J"
				(at 52.07 0 0)
				(effects
					(font
						(size 1.27 1.27)
					)
					(justify left bottom)
				)
			)
			(property "Value" "PCB-Edge_SODIMM_2x131_LPDDR5_Testbed"
				(at 52.07 -2.54 0)
				(effects
					(font
						(size 1.27 1.27)
					)
					(justify left bottom)
				)
			)
			(property "Footprint" "antmicro-footprints:PCB-Edge_SODIMM_2x131_DDR5"
				(at 52.07 -12.7 0)
				(effects
					(font
						(size 1.27 1.27)
					)
					(justify left bottom)
					(hide yes)
				)
			)
			(property "Datasheet" "https://cdn.amphenol-cs.com/media/wysiwyg/files/drawing/10162416.pdf"
				(at 52.07 -10.16 0)
				(effects
					(font
						(size 1.27 1.27)
					)
					(justify left bottom)
					(hide yes)
				)
			)
			(property "Description" "Memory Card Connector, LPDDR5 SO-DIMM, PCB Edge"
				(at 52.07 -20.32 0)
				(effects
					(font
						(size 1.27 1.27)
					)
					(justify left bottom)
					(hide yes)
				)
			)
			(property "MPN" ""
				(at 52.07 -7.62 0)
				(effects
					(font
						(size 1.27 1.27)
					)
					(justify left bottom)
				)
			)
			(property "Manufacturer" ""
				(at 52.07 -5.08 0)
				(effects
					(font
						(size 1.27 1.27)
					)
					(justify left bottom)
					(hide yes)
				)
			)
			(property "Author" "Antmicro"
				(at 52.07 -17.78 0)
				(effects
					(font
						(size 1.27 1.27)
					)
					(justify left bottom)
					(hide yes)
				)
			)
			(property "License" "Apache-2.0"
				(at 52.07 -15.24 0)
				(effects
					(font
						(size 1.27 1.27)
					)
					(justify left bottom)
					(hide yes)
				)
			)
			(property "ki_locked" ""
				(at 0 0 0)
				(effects
					(font
						(size 1.27 1.27)
					)
				)
			)
			(property "ki_keywords" "EDGE, CONNECTOR, DDR"
				(at 0 0 0)
				(effects
					(font
						(size 1.27 1.27)
					)
					(hide yes)
				)
			)
			(symbol "PCB-Edge_SODIMM_2x131_LPDDR5_Testbed_0_0"
				(text ""
					(at -5.08 60.96 0)
					(effects
						(font
							(size 1.27 1.27)
						)
					)
				)
			)
			(symbol "PCB-Edge_SODIMM_2x131_LPDDR5_Testbed_1_0"
				(pin passive line
					(at 0 0 0)
					(length 3.81)
					(name "VIN_BULK"
						(effects
							(font
								(size 1.016 1.016)
							)
						)
					)
					(number "1"
						(effects
							(font
								(size 1.016 1.016)
							)
						)
					)
				)
				(pin passive line
					(at 0 0 0)
					(length 3.81)
					(hide yes)
					(name "VIN_BULK"
						(effects
							(font
								(size 1.016 1.016)
							)
						)
					)
					(number "3"
						(effects
							(font
								(size 1.016 1.016)
							)
						)
					)
				)
				(pin input line
					(at 0 -10.16 0)
					(length 3.81)
					(name "TB_DETECT"
						(effects
							(font
								(size 1.016 1.016)
							)
						)
					)
					(number "130"
						(effects
							(font
								(size 1.016 1.016)
							)
						)
					)
				)
				(pin passive line
					(at 0 -12.7 0)
					(length 3.81)
					(name "RFU"
						(effects
							(font
								(size 1.016 1.016)
							)
						)
					)
					(number "5"
						(effects
							(font
								(size 1.016 1.016)
							)
						)
					)
				)
				(pin passive line
					(at 0 -15.24 0)
					(length 3.81)
					(name "RFU"
						(effects
							(font
								(size 1.016 1.016)
							)
						)
					)
					(number "128"
						(effects
							(font
								(size 1.016 1.016)
							)
						)
					)
				)
				(pin passive line
					(at 0 -17.78 0)
					(length 3.81)
					(name "RFU"
						(effects
							(font
								(size 1.016 1.016)
							)
						)
					)
					(number "143"
						(effects
							(font
								(size 1.016 1.016)
							)
						)
					)
				)
				(pin passive line
					(at 0 -20.32 0)
					(length 3.81)
					(name "VSS"
						(effects
							(font
								(size 1.016 1.016)
							)
						)
					)
					(number "10"
						(effects
							(font
								(size 1.016 1.016)
							)
						)
					)
				)
				(pin passive line
					(at 0 -20.32 0)
					(length 3.81)
					(hide yes)
					(name "VSS"
						(effects
							(font
								(size 1.016 1.016)
							)
						)
					)
					(number "101"
						(effects
							(font
								(size 1.016 1.016)
							)
						)
					)
				)
				(pin passive line
					(at 0 -20.32 0)
					(length 3.81)
					(hide yes)
					(name "VSS"
						(effects
							(font
								(size 1.016 1.016)
							)
						)
					)
					(number "104"
						(effects
							(font
								(size 1.016 1.016)
							)
						)
					)
				)
				(pin passive line
					(at 0 -20.32 0)
					(length 3.81)
					(hide yes)
					(name "VSS"
						(effects
							(font
								(size 1.016 1.016)
							)
						)
					)
					(number "105"
						(effects
							(font
								(size 1.016 1.016)
							)
						)
					)
				)
				(pin passive line
					(at 0 -20.32 0)
					(length 3.81)
					(hide yes)
					(name "VSS"
						(effects
							(font
								(size 1.016 1.016)
							)
						)
					)
					(number "111"
						(effects
							(font
								(size 1.016 1.016)
							)
						)
					)
				)
				(pin passive line
					(at 0 -20.32 0)
					(length 3.81)
					(hide yes)
					(name "VSS"
						(effects
							(font
								(size 1.016 1.016)
							)
						)
					)
					(number "112"
						(effects
							(font
								(size 1.016 1.016)
							)
						)
					)
				)
				(pin passive line
					(at 0 -20.32 0)
					(length 3.81)
					(hide yes)
					(name "VSS"
						(effects
							(font
								(size 1.016 1.016)
							)
						)
					)
					(number "117"
						(effects
							(font
								(size 1.016 1.016)
							)
						)
					)
				)
				(pin passive line
					(at 0 -20.32 0)
					(length 3.81)
					(hide yes)
					(name "VSS"
						(effects
							(font
								(size 1.016 1.016)
							)
						)
					)
					(number "118"
						(effects
							(font
								(size 1.016 1.016)
							)
						)
					)
				)
				(pin passive line
					(at 0 -20.32 0)
					(length 3.81)
					(hide yes)
					(name "VSS"
						(effects
							(font
								(size 1.016 1.016)
							)
						)
					)
					(number "123"
						(effects
							(font
								(size 1.016 1.016)
							)
						)
					)
				)
				(pin passive line
					(at 0 -20.32 0)
					(length 3.81)
					(hide yes)
					(name "VSS"
						(effects
							(font
								(size 1.016 1.016)
							)
						)
					)
					(number "124"
						(effects
							(font
								(size 1.016 1.016)
							)
						)
					)
				)
				(pin passive line
					(at 0 -20.32 0)
					(length 3.81)
					(hide yes)
					(name "VSS"
						(effects
							(font
								(size 1.016 1.016)
							)
						)
					)
					(number "129"
						(effects
							(font
								(size 1.016 1.016)
							)
						)
					)
				)
				(pin passive line
					(at 0 -20.32 0)
					(length 3.81)
					(hide yes)
					(name "VSS"
						(effects
							(font
								(size 1.016 1.016)
							)
						)
					)
					(number "13"
						(effects
							(font
								(size 1.016 1.016)
							)
						)
					)
				)
				(pin passive line
					(at 0 -20.32 0)
					(length 3.81)
					(hide yes)
					(name "VSS"
						(effects
							(font
								(size 1.016 1.016)
							)
						)
					)
					(number "135"
						(effects
							(font
								(size 1.016 1.016)
							)
						)
					)
				)
				(pin passive line
					(at 0 -20.32 0)
					(length 3.81)
					(hide yes)
					(name "VSS"
						(effects
							(font
								(size 1.016 1.016)
							)
						)
					)
					(number "136"
						(effects
							(font
								(size 1.016 1.016)
							)
						)
					)
				)
				(pin passive line
					(at 0 -20.32 0)
					(length 3.81)
					(hide yes)
					(name "VSS"
						(effects
							(font
								(size 1.016 1.016)
							)
						)
					)
					(number "14"
						(effects
							(font
								(size 1.016 1.016)
							)
						)
					)
				)
				(pin passive line
					(at 0 -20.32 0)
					(length 3.81)
					(hide yes)
					(name "VSS"
						(effects
							(font
								(size 1.016 1.016)
							)
						)
					)
					(number "141"
						(effects
							(font
								(size 1.016 1.016)
							)
						)
					)
				)
				(pin passive line
					(at 0 -20.32 0)
					(length 3.81)
					(hide yes)
					(name "VSS"
						(effects
							(font
								(size 1.016 1.016)
							)
						)
					)
					(number "142"
						(effects
							(font
								(size 1.016 1.016)
							)
						)
					)
				)
				(pin passive line
					(at 0 -20.32 0)
					(length 3.81)
					(hide yes)
					(name "VSS"
						(effects
							(font
								(size 1.016 1.016)
							)
						)
					)
					(number "147"
						(effects
							(font
								(size 1.016 1.016)
							)
						)
					)
				)
				(pin passive line
					(at 0 -20.32 0)
					(length 3.81)
					(hide yes)
					(name "VSS"
						(effects
							(font
								(size 1.016 1.016)
							)
						)
					)
					(number "148"
						(effects
							(font
								(size 1.016 1.016)
							)
						)
					)
				)
				(pin passive line
					(at 0 -20.32 0)
					(length 3.81)
					(hide yes)
					(name "VSS"
						(effects
							(font
								(size 1.016 1.016)
							)
						)
					)
					(number "153"
						(effects
							(font
								(size 1.016 1.016)
							)
						)
					)
				)
				(pin passive line
					(at 0 -20.32 0)
					(length 3.81)
					(hide yes)
					(name "VSS"
						(effects
							(font
								(size 1.016 1.016)
							)
						)
					)
					(number "154"
						(effects
							(font
								(size 1.016 1.016)
							)
						)
					)
				)
				(pin passive line
					(at 0 -20.32 0)
					(length 3.81)
					(hide yes)
					(name "VSS"
						(effects
							(font
								(size 1.016 1.016)
							)
						)
					)
					(number "159"
						(effects
							(font
								(size 1.016 1.016)
							)
						)
					)
				)
				(pin passive line
					(at 0 -20.32 0)
					(length 3.81)
					(hide yes)
					(name "VSS"
						(effects
							(font
								(size 1.016 1.016)
							)
						)
					)
					(number "160"
						(effects
							(font
								(size 1.016 1.016)
							)
						)
					)
				)
				(pin passive line
					(at 0 -20.32 0)
					(length 3.81)
					(hide yes)
					(name "VSS"
						(effects
							(font
								(size 1.016 1.016)
							)
						)
					)
					(number "166"
						(effects
							(font
								(size 1.016 1.016)
							)
						)
					)
				)
				(pin passive line
					(at 0 -20.32 0)
					(length 3.81)
					(hide yes)
					(name "VSS"
						(effects
							(font
								(size 1.016 1.016)
							)
						)
					)
					(number "167"
						(effects
							(font
								(size 1.016 1.016)
							)
						)
					)
				)
				(pin passive line
					(at 0 -20.32 0)
					(length 3.81)
					(hide yes)
					(name "VSS"
						(effects
							(font
								(size 1.016 1.016)
							)
						)
					)
					(number "17"
						(effects
							(font
								(size 1.016 1.016)
							)
						)
					)
				)
				(pin passive line
					(at 0 -20.32 0)
					(length 3.81)
					(hide yes)
					(name "VSS"
						(effects
							(font
								(size 1.016 1.016)
							)
						)
					)
					(number "170"
						(effects
							(font
								(size 1.016 1.016)
							)
						)
					)
				)
				(pin passive line
					(at 0 -20.32 0)
					(length 3.81)
					(hide yes)
					(name "VSS"
						(effects
							(font
								(size 1.016 1.016)
							)
						)
					)
					(number "173"
						(effects
							(font
								(size 1.016 1.016)
							)
						)
					)
				)
				(pin passive line
					(at 0 -20.32 0)
					(length 3.81)
					(hide yes)
					(name "VSS"
						(effects
							(font
								(size 1.016 1.016)
							)
						)
					)
					(number "174"
						(effects
							(font
								(size 1.016 1.016)
							)
						)
					)
				)
				(pin passive line
					(at 0 -20.32 0)
					(length 3.81)
					(hide yes)
					(name "VSS"
						(effects
							(font
								(size 1.016 1.016)
							)
						)
					)
					(number "177"
						(effects
							(font
								(size 1.016 1.016)
							)
						)
					)
				)
				(pin passive line
					(at 0 -20.32 0)
					(length 3.81)
					(hide yes)
					(name "VSS"
						(effects
							(font
								(size 1.016 1.016)
							)
						)
					)
					(number "178"
						(effects
							(font
								(size 1.016 1.016)
							)
						)
					)
				)
				(pin passive line
					(at 0 -20.32 0)
					(length 3.81)
					(hide yes)
					(name "VSS"
						(effects
							(font
								(size 1.016 1.016)
							)
						)
					)
					(number "18"
						(effects
							(font
								(size 1.016 1.016)
							)
						)
					)
				)
				(pin passive line
					(at 0 -20.32 0)
					(length 3.81)
					(hide yes)
					(name "VSS"
						(effects
							(font
								(size 1.016 1.016)
							)
						)
					)
					(number "181"
						(effects
							(font
								(size 1.016 1.016)
							)
						)
					)
				)
				(pin passive line
					(at 0 -20.32 0)
					(length 3.81)
					(hide yes)
					(name "VSS"
						(effects
							(font
								(size 1.016 1.016)
							)
						)
					)
					(number "182"
						(effects
							(font
								(size 1.016 1.016)
							)
						)
					)
				)
				(pin passive line
					(at 0 -20.32 0)
					(length 3.81)
					(hide yes)
					(name "VSS"
						(effects
							(font
								(size 1.016 1.016)
							)
						)
					)
					(number "185"
						(effects
							(font
								(size 1.016 1.016)
							)
						)
					)
				)
				(pin passive line
					(at 0 -20.32 0)
					(length 3.81)
					(hide yes)
					(name "VSS"
						(effects
							(font
								(size 1.016 1.016)
							)
						)
					)
					(number "186"
						(effects
							(font
								(size 1.016 1.016)
							)
						)
					)
				)
				(pin passive line
					(at 0 -20.32 0)
					(length 3.81)
					(hide yes)
					(name "VSS"
						(effects
							(font
								(size 1.016 1.016)
							)
						)
					)
					(number "189"
						(effects
							(font
								(size 1.016 1.016)
							)
						)
					)
				)
				(pin passive line
					(at 0 -20.32 0)
					(length 3.81)
					(hide yes)
					(name "VSS"
						(effects
							(font
								(size 1.016 1.016)
							)
						)
					)
					(number "192"
						(effects
							(font
								(size 1.016 1.016)
							)
						)
					)
				)
				(pin passive line
					(at 0 -20.32 0)
					(length 3.81)
					(hide yes)
					(name "VSS"
						(effects
							(font
								(size 1.016 1.016)
							)
						)
					)
					(number "193"
						(effects
							(font
								(size 1.016 1.016)
							)
						)
					)
				)
				(pin passive line
					(at 0 -20.32 0)
					(length 3.81)
					(hide yes)
					(name "VSS"
						(effects
							(font
								(size 1.016 1.016)
							)
						)
					)
					(number "196"
						(effects
							(font
								(size 1.016 1.016)
							)
						)
					)
				)
				(pin passive line
					(at 0 -20.32 0)
					(length 3.81)
					(hide yes)
					(name "VSS"
						(effects
							(font
								(size 1.016 1.016)
							)
						)
					)
					(number "197"
						(effects
							(font
								(size 1.016 1.016)
							)
						)
					)
				)
				(pin passive line
					(at 0 -20.32 0)
					(length 3.81)
					(hide yes)
					(name "VSS"
						(effects
							(font
								(size 1.016 1.016)
							)
						)
					)
					(number "200"
						(effects
							(font
								(size 1.016 1.016)
							)
						)
					)
				)
				(pin passive line
					(at 0 -20.32 0)
					(length 3.81)
					(hide yes)
					(name "VSS"
						(effects
							(font
								(size 1.016 1.016)
							)
						)
					)
					(number "201"
						(effects
							(font
								(size 1.016 1.016)
							)
						)
					)
				)
				(pin passive line
					(at 0 -20.32 0)
					(length 3.81)
					(hide yes)
					(name "VSS"
						(effects
							(font
								(size 1.016 1.016)
							)
						)
					)
					(number "204"
						(effects
							(font
								(size 1.016 1.016)
							)
						)
					)
				)
				(pin passive line
					(at 0 -20.32 0)
					(length 3.81)
					(hide yes)
					(name "VSS"
						(effects
							(font
								(size 1.016 1.016)
							)
						)
					)
					(number "205"
						(effects
							(font
								(size 1.016 1.016)
							)
						)
					)
				)
				(pin passive line
					(at 0 -20.32 0)
					(length 3.81)
					(hide yes)
					(name "VSS"
						(effects
							(font
								(size 1.016 1.016)
							)
						)
					)
					(number "208"
						(effects
							(font
								(size 1.016 1.016)
							)
						)
					)
				)
				(pin passive line
					(at 0 -20.32 0)
					(length 3.81)
					(hide yes)
					(name "VSS"
						(effects
							(font
								(size 1.016 1.016)
							)
						)
					)
					(number "21"
						(effects
							(font
								(size 1.016 1.016)
							)
						)
					)
				)
				(pin passive line
					(at 0 -20.32 0)
					(length 3.81)
					(hide yes)
					(name "VSS"
						(effects
							(font
								(size 1.016 1.016)
							)
						)
					)
					(number "211"
						(effects
							(font
								(size 1.016 1.016)
							)
						)
					)
				)
				(pin passive line
					(at 0 -20.32 0)
					(length 3.81)
					(hide yes)
					(name "VSS"
						(effects
							(font
								(size 1.016 1.016)
							)
						)
					)
					(number "212"
						(effects
							(font
								(size 1.016 1.016)
							)
						)
					)
				)
				(pin passive line
					(at 0 -20.32 0)
					(length 3.81)
					(hide yes)
					(name "VSS"
						(effects
							(font
								(size 1.016 1.016)
							)
						)
					)
					(number "215"
						(effects
							(font
								(size 1.016 1.016)
							)
						)
					)
				)
				(pin passive line
					(at 0 -20.32 0)
					(length 3.81)
					(hide yes)
					(name "VSS"
						(effects
							(font
								(size 1.016 1.016)
							)
						)
					)
					(number "216"
						(effects
							(font
								(size 1.016 1.016)
							)
						)
					)
				)
				(pin passive line
					(at 0 -20.32 0)
					(length 3.81)
					(hide yes)
					(name "VSS"
						(effects
							(font
								(size 1.016 1.016)
							)
						)
					)
					(number "219"
						(effects
							(font
								(size 1.016 1.016)
							)
						)
					)
				)
				(pin passive line
					(at 0 -20.32 0)
					(length 3.81)
					(hide yes)
					(name "VSS"
						(effects
							(font
								(size 1.016 1.016)
							)
						)
					)
					(number "220"
						(effects
							(font
								(size 1.016 1.016)
							)
						)
					)
				)
				(pin passive line
					(at 0 -20.32 0)
					(length 3.81)
					(hide yes)
					(name "VSS"
						(effects
							(font
								(size 1.016 1.016)
							)
						)
					)
					(number "223"
						(effects
							(font
								(size 1.016 1.016)
							)
						)
					)
				)
				(pin passive line
					(at 0 -20.32 0)
					(length 3.81)
					(hide yes)
					(name "VSS"
						(effects
							(font
								(size 1.016 1.016)
							)
						)
					)
					(number "224"
						(effects
							(font
								(size 1.016 1.016)
							)
						)
					)
				)
				(pin passive line
					(at 0 -20.32 0)
					(length 3.81)
					(hide yes)
					(name "VSS"
						(effects
							(font
								(size 1.016 1.016)
							)
						)
					)
					(number "227"
						(effects
							(font
								(size 1.016 1.016)
							)
						)
					)
				)
				(pin passive line
					(at 0 -20.32 0)
					(length 3.81)
					(hide yes)
					(name "VSS"
						(effects
							(font
								(size 1.016 1.016)
							)
						)
					)
					(number "228"
						(effects
							(font
								(size 1.016 1.016)
							)
						)
					)
				)
				(pin passive line
					(at 0 -20.32 0)
					(length 3.81)
					(hide yes)
					(name "VSS"
						(effects
							(font
								(size 1.016 1.016)
							)
						)
					)
					(number "231"
						(effects
							(font
								(size 1.016 1.016)
							)
						)
					)
				)
				(pin passive line
					(at 0 -20.32 0)
					(length 3.81)
					(hide yes)
					(name "VSS"
						(effects
							(font
								(size 1.016 1.016)
							)
						)
					)
					(number "234"
						(effects
							(font
								(size 1.016 1.016)
							)
						)
					)
				)
				(pin passive line
					(at 0 -20.32 0)
					(length 3.81)
					(hide yes)
					(name "VSS"
						(effects
							(font
								(size 1.016 1.016)
							)
						)
					)
					(number "235"
						(effects
							(font
								(size 1.016 1.016)
							)
						)
					)
				)
				(pin passive line
					(at 0 -20.32 0)
					(length 3.81)
					(hide yes)
					(name "VSS"
						(effects
							(font
								(size 1.016 1.016)
							)
						)
					)
					(number "238"
						(effects
							(font
								(size 1.016 1.016)
							)
						)
					)
				)
				(pin passive line
					(at 0 -20.32 0)
					(length 3.81)
					(hide yes)
					(name "VSS"
						(effects
							(font
								(size 1.016 1.016)
							)
						)
					)
					(number "239"
						(effects
							(font
								(size 1.016 1.016)
							)
						)
					)
				)
				(pin passive line
					(at 0 -20.32 0)
					(length 3.81)
					(hide yes)
					(name "VSS"
						(effects
							(font
								(size 1.016 1.016)
							)
						)
					)
					(number "24"
						(effects
							(font
								(size 1.016 1.016)
							)
						)
					)
				)
				(pin passive line
					(at 0 -20.32 0)
					(length 3.81)
					(hide yes)
					(name "VSS"
						(effects
							(font
								(size 1.016 1.016)
							)
						)
					)
					(number "242"
						(effects
							(font
								(size 1.016 1.016)
							)
						)
					)
				)
				(pin passive line
					(at 0 -20.32 0)
					(length 3.81)
					(hide yes)
					(name "VSS"
						(effects
							(font
								(size 1.016 1.016)
							)
						)
					)
					(number "243"
						(effects
							(font
								(size 1.016 1.016)
							)
						)
					)
				)
				(pin passive line
					(at 0 -20.32 0)
					(length 3.81)
					(hide yes)
					(name "VSS"
						(effects
							(font
								(size 1.016 1.016)
							)
						)
					)
					(number "246"
						(effects
							(font
								(size 1.016 1.016)
							)
						)
					)
				)
				(pin passive line
					(at 0 -20.32 0)
					(length 3.81)
					(hide yes)
					(name "VSS"
						(effects
							(font
								(size 1.016 1.016)
							)
						)
					)
					(number "247"
						(effects
							(font
								(size 1.016 1.016)
							)
						)
					)
				)
				(pin passive line
					(at 0 -20.32 0)
					(length 3.81)
					(hide yes)
					(name "VSS"
						(effects
							(font
								(size 1.016 1.016)
							)
						)
					)
					(number "25"
						(effects
							(font
								(size 1.016 1.016)
							)
						)
					)
				)
				(pin passive line
					(at 0 -20.32 0)
					(length 3.81)
					(hide yes)
					(name "VSS"
						(effects
							(font
								(size 1.016 1.016)
							)
						)
					)
					(number "250"
						(effects
							(font
								(size 1.016 1.016)
							)
						)
					)
				)
				(pin passive line
					(at 0 -20.32 0)
					(length 3.81)
					(hide yes)
					(name "VSS"
						(effects
							(font
								(size 1.016 1.016)
							)
						)
					)
					(number "253"
						(effects
							(font
								(size 1.016 1.016)
							)
						)
					)
				)
				(pin passive line
					(at 0 -20.32 0)
					(length 3.81)
					(hide yes)
					(name "VSS"
						(effects
							(font
								(size 1.016 1.016)
							)
						)
					)
					(number "254"
						(effects
							(font
								(size 1.016 1.016)
							)
						)
					)
				)
				(pin passive line
					(at 0 -20.32 0)
					(length 3.81)
					(hide yes)
					(name "VSS"
						(effects
							(font
								(size 1.016 1.016)
							)
						)
					)
					(number "257"
						(effects
							(font
								(size 1.016 1.016)
							)
						)
					)
				)
				(pin passive line
					(at 0 -20.32 0)
					(length 3.81)
					(hide yes)
					(name "VSS"
						(effects
							(font
								(size 1.016 1.016)
							)
						)
					)
					(number "258"
						(effects
							(font
								(size 1.016 1.016)
							)
						)
					)
				)
				(pin passive line
					(at 0 -20.32 0)
					(length 3.81)
					(hide yes)
					(name "VSS"
						(effects
							(font
								(size 1.016 1.016)
							)
						)
					)
					(number "261"
						(effects
							(font
								(size 1.016 1.016)
							)
						)
					)
				)
				(pin passive line
					(at 0 -20.32 0)
					(length 3.81)
					(hide yes)
					(name "VSS"
						(effects
							(font
								(size 1.016 1.016)
							)
						)
					)
					(number "262"
						(effects
							(font
								(size 1.016 1.016)
							)
						)
					)
				)
				(pin passive line
					(at 0 -20.32 0)
					(length 3.81)
					(hide yes)
					(name "VSS"
						(effects
							(font
								(size 1.016 1.016)
							)
						)
					)
					(number "28"
						(effects
							(font
								(size 1.016 1.016)
							)
						)
					)
				)
				(pin passive line
					(at 0 -20.32 0)
					(length 3.81)
					(hide yes)
					(name "VSS"
						(effects
							(font
								(size 1.016 1.016)
							)
						)
					)
					(number "29"
						(effects
							(font
								(size 1.016 1.016)
							)
						)
					)
				)
				(pin passive line
					(at 0 -20.32 0)
					(length 3.81)
					(hide yes)
					(name "VSS"
						(effects
							(font
								(size 1.016 1.016)
							)
						)
					)
					(number "32"
						(effects
							(font
								(size 1.016 1.016)
							)
						)
					)
				)
				(pin passive line
					(at 0 -20.32 0)
					(length 3.81)
					(hide yes)
					(name "VSS"
						(effects
							(font
								(size 1.016 1.016)
							)
						)
					)
					(number "33"
						(effects
							(font
								(size 1.016 1.016)
							)
						)
					)
				)
				(pin passive line
					(at 0 -20.32 0)
					(length 3.81)
					(hide yes)
					(name "VSS"
						(effects
							(font
								(size 1.016 1.016)
							)
						)
					)
					(number "36"
						(effects
							(font
								(size 1.016 1.016)
							)
						)
					)
				)
				(pin passive line
					(at 0 -20.32 0)
					(length 3.81)
					(hide yes)
					(name "VSS"
						(effects
							(font
								(size 1.016 1.016)
							)
						)
					)
					(number "37"
						(effects
							(font
								(size 1.016 1.016)
							)
						)
					)
				)
				(pin passive line
					(at 0 -20.32 0)
					(length 3.81)
					(hide yes)
					(name "VSS"
						(effects
							(font
								(size 1.016 1.016)
							)
						)
					)
					(number "40"
						(effects
							(font
								(size 1.016 1.016)
							)
						)
					)
				)
				(pin passive line
					(at 0 -20.32 0)
					(length 3.81)
					(hide yes)
					(name "VSS"
						(effects
							(font
								(size 1.016 1.016)
							)
						)
					)
					(number "43"
						(effects
							(font
								(size 1.016 1.016)
							)
						)
					)
				)
				(pin passive line
					(at 0 -20.32 0)
					(length 3.81)
					(hide yes)
					(name "VSS"
						(effects
							(font
								(size 1.016 1.016)
							)
						)
					)
					(number "44"
						(effects
							(font
								(size 1.016 1.016)
							)
						)
					)
				)
				(pin passive line
					(at 0 -20.32 0)
					(length 3.81)
					(hide yes)
					(name "VSS"
						(effects
							(font
								(size 1.016 1.016)
							)
						)
					)
					(number "47"
						(effects
							(font
								(size 1.016 1.016)
							)
						)
					)
				)
				(pin passive line
					(at 0 -20.32 0)
					(length 3.81)
					(hide yes)
					(name "VSS"
						(effects
							(font
								(size 1.016 1.016)
							)
						)
					)
					(number "48"
						(effects
							(font
								(size 1.016 1.016)
							)
						)
					)
				)
				(pin passive line
					(at 0 -20.32 0)
					(length 3.81)
					(hide yes)
					(name "VSS"
						(effects
							(font
								(size 1.016 1.016)
							)
						)
					)
					(number "51"
						(effects
							(font
								(size 1.016 1.016)
							)
						)
					)
				)
				(pin passive line
					(at 0 -20.32 0)
					(length 3.81)
					(hide yes)
					(name "VSS"
						(effects
							(font
								(size 1.016 1.016)
							)
						)
					)
					(number "52"
						(effects
							(font
								(size 1.016 1.016)
							)
						)
					)
				)
				(pin passive line
					(at 0 -20.32 0)
					(length 3.81)
					(hide yes)
					(name "VSS"
						(effects
							(font
								(size 1.016 1.016)
							)
						)
					)
					(number "55"
						(effects
							(font
								(size 1.016 1.016)
							)
						)
					)
				)
				(pin passive line
					(at 0 -20.32 0)
					(length 3.81)
					(hide yes)
					(name "VSS"
						(effects
							(font
								(size 1.016 1.016)
							)
						)
					)
					(number "56"
						(effects
							(font
								(size 1.016 1.016)
							)
						)
					)
				)
				(pin passive line
					(at 0 -20.32 0)
					(length 3.81)
					(hide yes)
					(name "VSS"
						(effects
							(font
								(size 1.016 1.016)
							)
						)
					)
					(number "59"
						(effects
							(font
								(size 1.016 1.016)
							)
						)
					)
				)
				(pin passive line
					(at 0 -20.32 0)
					(length 3.81)
					(hide yes)
					(name "VSS"
						(effects
							(font
								(size 1.016 1.016)
							)
						)
					)
					(number "60"
						(effects
							(font
								(size 1.016 1.016)
							)
						)
					)
				)
				(pin passive line
					(at 0 -20.32 0)
					(length 3.81)
					(hide yes)
					(name "VSS"
						(effects
							(font
								(size 1.016 1.016)
							)
						)
					)
					(number "63"
						(effects
							(font
								(size 1.016 1.016)
							)
						)
					)
				)
				(pin passive line
					(at 0 -20.32 0)
					(length 3.81)
					(hide yes)
					(name "VSS"
						(effects
							(font
								(size 1.016 1.016)
							)
						)
					)
					(number "66"
						(effects
							(font
								(size 1.016 1.016)
							)
						)
					)
				)
				(pin passive line
					(at 0 -20.32 0)
					(length 3.81)
					(hide yes)
					(name "VSS"
						(effects
							(font
								(size 1.016 1.016)
							)
						)
					)
					(number "67"
						(effects
							(font
								(size 1.016 1.016)
							)
						)
					)
				)
				(pin passive line
					(at 0 -20.32 0)
					(length 3.81)
					(hide yes)
					(name "VSS"
						(effects
							(font
								(size 1.016 1.016)
							)
						)
					)
					(number "70"
						(effects
							(font
								(size 1.016 1.016)
							)
						)
					)
				)
				(pin passive line
					(at 0 -20.32 0)
					(length 3.81)
					(hide yes)
					(name "VSS"
						(effects
							(font
								(size 1.016 1.016)
							)
						)
					)
					(number "71"
						(effects
							(font
								(size 1.016 1.016)
							)
						)
					)
				)
				(pin passive line
					(at 0 -20.32 0)
					(length 3.81)
					(hide yes)
					(name "VSS"
						(effects
							(font
								(size 1.016 1.016)
							)
						)
					)
					(number "74"
						(effects
							(font
								(size 1.016 1.016)
							)
						)
					)
				)
				(pin passive line
					(at 0 -20.32 0)
					(length 3.81)
					(hide yes)
					(name "VSS"
						(effects
							(font
								(size 1.016 1.016)
							)
						)
					)
					(number "75"
						(effects
							(font
								(size 1.016 1.016)
							)
						)
					)
				)
				(pin passive line
					(at 0 -20.32 0)
					(length 3.81)
					(hide yes)
					(name "VSS"
						(effects
							(font
								(size 1.016 1.016)
							)
						)
					)
					(number "78"
						(effects
							(font
								(size 1.016 1.016)
							)
						)
					)
				)
				(pin passive line
					(at 0 -20.32 0)
					(length 3.81)
					(hide yes)
					(name "VSS"
						(effects
							(font
								(size 1.016 1.016)
							)
						)
					)
					(number "79"
						(effects
							(font
								(size 1.016 1.016)
							)
						)
					)
				)
				(pin passive line
					(at 0 -20.32 0)
					(length 3.81)
					(hide yes)
					(name "VSS"
						(effects
							(font
								(size 1.016 1.016)
							)
						)
					)
					(number "82"
						(effects
							(font
								(size 1.016 1.016)
							)
						)
					)
				)
				(pin passive line
					(at 0 -20.32 0)
					(length 3.81)
					(hide yes)
					(name "VSS"
						(effects
							(font
								(size 1.016 1.016)
							)
						)
					)
					(number "85"
						(effects
							(font
								(size 1.016 1.016)
							)
						)
					)
				)
				(pin passive line
					(at 0 -20.32 0)
					(length 3.81)
					(hide yes)
					(name "VSS"
						(effects
							(font
								(size 1.016 1.016)
							)
						)
					)
					(number "86"
						(effects
							(font
								(size 1.016 1.016)
							)
						)
					)
				)
				(pin passive line
					(at 0 -20.32 0)
					(length 3.81)
					(hide yes)
					(name "VSS"
						(effects
							(font
								(size 1.016 1.016)
							)
						)
					)
					(number "89"
						(effects
							(font
								(size 1.016 1.016)
							)
						)
					)
				)
				(pin passive line
					(at 0 -20.32 0)
					(length 3.81)
					(hide yes)
					(name "VSS"
						(effects
							(font
								(size 1.016 1.016)
							)
						)
					)
					(number "9"
						(effects
							(font
								(size 1.016 1.016)
							)
						)
					)
				)
				(pin passive line
					(at 0 -20.32 0)
					(length 3.81)
					(hide yes)
					(name "VSS"
						(effects
							(font
								(size 1.016 1.016)
							)
						)
					)
					(number "90"
						(effects
							(font
								(size 1.016 1.016)
							)
						)
					)
				)
				(pin passive line
					(at 0 -20.32 0)
					(length 3.81)
					(hide yes)
					(name "VSS"
						(effects
							(font
								(size 1.016 1.016)
							)
						)
					)
					(number "93"
						(effects
							(font
								(size 1.016 1.016)
							)
						)
					)
				)
				(pin passive line
					(at 0 -20.32 0)
					(length 3.81)
					(hide yes)
					(name "VSS"
						(effects
							(font
								(size 1.016 1.016)
							)
						)
					)
					(number "94"
						(effects
							(font
								(size 1.016 1.016)
							)
						)
					)
				)
				(pin passive line
					(at 0 -20.32 0)
					(length 3.81)
					(hide yes)
					(name "VSS"
						(effects
							(font
								(size 1.016 1.016)
							)
						)
					)
					(number "97"
						(effects
							(font
								(size 1.016 1.016)
							)
						)
					)
				)
				(pin passive line
					(at 0 -20.32 0)
					(length 3.81)
					(hide yes)
					(name "VSS"
						(effects
							(font
								(size 1.016 1.016)
							)
						)
					)
					(number "98"
						(effects
							(font
								(size 1.016 1.016)
							)
						)
					)
				)
				(pin passive line
					(at 25.4 0 180)
					(length 3.81)
					(name "PWR_EN"
						(effects
							(font
								(size 1.016 1.016)
							)
						)
					)
					(number "8"
						(effects
							(font
								(size 1.016 1.016)
							)
						)
					)
				)
				(pin passive line
					(at 25.4 -2.54 180)
					(length 3.81)
					(name "RESET_n"
						(effects
							(font
								(size 1.016 1.016)
							)
						)
					)
					(number "163"
						(effects
							(font
								(size 1.016 1.016)
							)
						)
					)
				)
				(pin passive line
					(at 25.4 -7.62 180)
					(length 3.81)
					(name "HSA"
						(effects
							(font
								(size 1.016 1.016)
							)
						)
					)
					(number "2"
						(effects
							(font
								(size 1.016 1.016)
							)
						)
					)
				)
				(pin passive line
					(at 25.4 -10.16 180)
					(length 3.81)
					(name "HSCL"
						(effects
							(font
								(size 1.016 1.016)
							)
						)
					)
					(number "4"
						(effects
							(font
								(size 1.016 1.016)
							)
						)
					)
				)
				(pin passive line
					(at 25.4 -12.7 180)
					(length 3.81)
					(name "HSDA"
						(effects
							(font
								(size 1.016 1.016)
							)
						)
					)
					(number "6"
						(effects
							(font
								(size 1.016 1.016)
							)
						)
					)
				)
				(pin passive line
					(at 25.4 -17.78 180)
					(length 3.81)
					(name "PWR_GOOD"
						(effects
							(font
								(size 1.016 1.016)
							)
						)
					)
					(number "7"
						(effects
							(font
								(size 1.016 1.016)
							)
						)
					)
				)
				(pin passive line
					(at 25.4 -20.32 180)
					(length 3.81)
					(name "ALERT_n"
						(effects
							(font
								(size 1.016 1.016)
							)
						)
					)
					(number "108"
						(effects
							(font
								(size 1.016 1.016)
							)
						)
					)
				)
			)
			(symbol "PCB-Edge_SODIMM_2x131_LPDDR5_Testbed_1_1"
				(rectangle
					(start 3.81 2.54)
					(end 21.59 -22.86)
					(stroke
						(width 0)
						(type default)
					)
					(fill
						(type background)
					)
				)
			)
			(symbol "PCB-Edge_SODIMM_2x131_LPDDR5_Testbed_2_0"
				(pin passive line
					(at 0 0 0)
					(length 3.81)
					(name "CS0_A_n"
						(effects
							(font
								(size 1.016 1.016)
							)
						)
					)
					(number "106"
						(effects
							(font
								(size 1.016 1.016)
							)
						)
					)
				)
				(pin passive line
					(at 0 -2.54 0)
					(length 3.81)
					(name "CS1_A_n"
						(effects
							(font
								(size 1.016 1.016)
							)
						)
					)
					(number "110"
						(effects
							(font
								(size 1.016 1.016)
							)
						)
					)
				)
				(pin passive line
					(at 0 -10.16 0)
					(length 3.81)
					(name "DM0_A_n"
						(effects
							(font
								(size 1.016 1.016)
							)
						)
					)
					(number "19"
						(effects
							(font
								(size 1.016 1.016)
							)
						)
					)
				)
				(pin passive line
					(at 0 -12.7 0)
					(length 3.81)
					(name "DM1_A_n"
						(effects
							(font
								(size 1.016 1.016)
							)
						)
					)
					(number "42"
						(effects
							(font
								(size 1.016 1.016)
							)
						)
					)
				)
				(pin passive line
					(at 0 -15.24 0)
					(length 3.81)
					(name "DM2_A_n"
						(effects
							(font
								(size 1.016 1.016)
							)
						)
					)
					(number "61"
						(effects
							(font
								(size 1.016 1.016)
							)
						)
					)
				)
				(pin passive line
					(at 0 -17.78 0)
					(length 3.81)
					(name "DM3_A_n"
						(effects
							(font
								(size 1.016 1.016)
							)
						)
					)
					(number "84"
						(effects
							(font
								(size 1.016 1.016)
							)
						)
					)
				)
				(pin passive line
					(at 0 -25.4 0)
					(length 3.81)
					(name "CK0_A_t"
						(effects
							(font
								(size 1.016 1.016)
							)
						)
					)
					(number "131"
						(effects
							(font
								(size 1.016 1.016)
							)
						)
					)
				)
				(pin passive line
					(at 0 -27.94 0)
					(length 3.81)
					(name "CK0_A_c"
						(effects
							(font
								(size 1.016 1.016)
							)
						)
					)
					(number "133"
						(effects
							(font
								(size 1.016 1.016)
							)
						)
					)
				)
				(pin passive line
					(at 0 -33.02 0)
					(length 3.81)
					(name "CK1_A_t"
						(effects
							(font
								(size 1.016 1.016)
							)
						)
					)
					(number "132"
						(effects
							(font
								(size 1.016 1.016)
							)
						)
					)
				)
				(pin passive line
					(at 0 -35.56 0)
					(length 3.81)
					(name "CK1_A_c"
						(effects
							(font
								(size 1.016 1.016)
							)
						)
					)
					(number "134"
						(effects
							(font
								(size 1.016 1.016)
							)
						)
					)
				)
				(pin passive line
					(at 0 -40.64 0)
					(length 3.81)
					(name "CA0_A"
						(effects
							(font
								(size 1.016 1.016)
							)
						)
					)
					(number "107"
						(effects
							(font
								(size 1.016 1.016)
							)
						)
					)
				)
				(pin passive line
					(at 0 -43.18 0)
					(length 3.81)
					(name "CA1_A"
						(effects
							(font
								(size 1.016 1.016)
							)
						)
					)
					(number "109"
						(effects
							(font
								(size 1.016 1.016)
							)
						)
					)
				)
				(pin passive line
					(at 0 -45.72 0)
					(length 3.81)
					(name "CA2_A"
						(effects
							(font
								(size 1.016 1.016)
							)
						)
					)
					(number "113"
						(effects
							(font
								(size 1.016 1.016)
							)
						)
					)
				)
				(pin passive line
					(at 0 -48.26 0)
					(length 3.81)
					(name "CA3_A"
						(effects
							(font
								(size 1.016 1.016)
							)
						)
					)
					(number "114"
						(effects
							(font
								(size 1.016 1.016)
							)
						)
					)
				)
				(pin passive line
					(at 0 -50.8 0)
					(length 3.81)
					(name "CA4_A"
						(effects
							(font
								(size 1.016 1.016)
							)
						)
					)
					(number "115"
						(effects
							(font
								(size 1.016 1.016)
							)
						)
					)
				)
				(pin passive line
					(at 0 -53.34 0)
					(length 3.81)
					(name "CA5_A"
						(effects
							(font
								(size 1.016 1.016)
							)
						)
					)
					(number "116"
						(effects
							(font
								(size 1.016 1.016)
							)
						)
					)
				)
				(pin passive line
					(at 0 -55.88 0)
					(length 3.81)
					(name "CA6_A"
						(effects
							(font
								(size 1.016 1.016)
							)
						)
					)
					(number "119"
						(effects
							(font
								(size 1.016 1.016)
							)
						)
					)
				)
				(pin passive line
					(at 0 -58.42 0)
					(length 3.81)
					(name "CA7_A"
						(effects
							(font
								(size 1.016 1.016)
							)
						)
					)
					(number "120"
						(effects
							(font
								(size 1.016 1.016)
							)
						)
					)
				)
				(pin passive line
					(at 0 -60.96 0)
					(length 3.81)
					(name "CA8_A"
						(effects
							(font
								(size 1.016 1.016)
							)
						)
					)
					(number "121"
						(effects
							(font
								(size 1.016 1.016)
							)
						)
					)
				)
				(pin passive line
					(at 0 -63.5 0)
					(length 3.81)
					(name "CA9_A"
						(effects
							(font
								(size 1.016 1.016)
							)
						)
					)
					(number "122"
						(effects
							(font
								(size 1.016 1.016)
							)
						)
					)
				)
				(pin passive line
					(at 0 -66.04 0)
					(length 3.81)
					(name "CA10_A"
						(effects
							(font
								(size 1.016 1.016)
							)
						)
					)
					(number "125"
						(effects
							(font
								(size 1.016 1.016)
							)
						)
					)
				)
				(pin passive line
					(at 0 -68.58 0)
					(length 3.81)
					(name "CA11_A"
						(effects
							(font
								(size 1.016 1.016)
							)
						)
					)
					(number "126"
						(effects
							(font
								(size 1.016 1.016)
							)
						)
					)
				)
				(pin passive line
					(at 0 -71.12 0)
					(length 3.81)
					(name "CA12_A"
						(effects
							(font
								(size 1.016 1.016)
							)
						)
					)
					(number "127"
						(effects
							(font
								(size 1.016 1.016)
							)
						)
					)
				)
				(pin passive line
					(at 0 -78.74 0)
					(length 3.81)
					(name "DQS4_A_t"
						(effects
							(font
								(size 1.016 1.016)
							)
						)
					)
					(number "102"
						(effects
							(font
								(size 1.016 1.016)
							)
						)
					)
				)
				(pin passive line
					(at 0 -81.28 0)
					(length 3.81)
					(name "DQS4_A_c"
						(effects
							(font
								(size 1.016 1.016)
							)
						)
					)
					(number "100"
						(effects
							(font
								(size 1.016 1.016)
							)
						)
					)
				)
				(pin passive line
					(at 0 -86.36 0)
					(length 3.81)
					(name "CB0_A"
						(effects
							(font
								(size 1.016 1.016)
							)
						)
					)
					(number "95"
						(effects
							(font
								(size 1.016 1.016)
							)
						)
					)
				)
				(pin passive line
					(at 0 -88.9 0)
					(length 3.81)
					(name "CB1_A"
						(effects
							(font
								(size 1.016 1.016)
							)
						)
					)
					(number "96"
						(effects
							(font
								(size 1.016 1.016)
							)
						)
					)
				)
				(pin passive line
					(at 0 -91.44 0)
					(length 3.81)
					(name "CB2_A"
						(effects
							(font
								(size 1.016 1.016)
							)
						)
					)
					(number "99"
						(effects
							(font
								(size 1.016 1.016)
							)
						)
					)
				)
				(pin passive line
					(at 0 -93.98 0)
					(length 3.81)
					(name "CB3_A"
						(effects
							(font
								(size 1.016 1.016)
							)
						)
					)
					(number "103"
						(effects
							(font
								(size 1.016 1.016)
							)
						)
					)
				)
				(pin passive line
					(at 35.56 0 180)
					(length 3.81)
					(name "DQS0_A_t"
						(effects
							(font
								(size 1.016 1.016)
							)
						)
					)
					(number "22"
						(effects
							(font
								(size 1.016 1.016)
							)
						)
					)
				)
				(pin passive line
					(at 35.56 -2.54 180)
					(length 3.81)
					(name "DQS0_A_C"
						(effects
							(font
								(size 1.016 1.016)
							)
						)
					)
					(number "20"
						(effects
							(font
								(size 1.016 1.016)
							)
						)
					)
				)
				(pin passive line
					(at 35.56 -7.62 180)
					(length 3.81)
					(name "DQ0_A"
						(effects
							(font
								(size 1.016 1.016)
							)
						)
					)
					(number "11"
						(effects
							(font
								(size 1.016 1.016)
							)
						)
					)
				)
				(pin passive line
					(at 35.56 -10.16 180)
					(length 3.81)
					(name "DQ1_A"
						(effects
							(font
								(size 1.016 1.016)
							)
						)
					)
					(number "12"
						(effects
							(font
								(size 1.016 1.016)
							)
						)
					)
				)
				(pin passive line
					(at 35.56 -12.7 180)
					(length 3.81)
					(name "DQ2_A"
						(effects
							(font
								(size 1.016 1.016)
							)
						)
					)
					(number "15"
						(effects
							(font
								(size 1.016 1.016)
							)
						)
					)
				)
				(pin passive line
					(at 35.56 -15.24 180)
					(length 3.81)
					(name "DQ3_A"
						(effects
							(font
								(size 1.016 1.016)
							)
						)
					)
					(number "16"
						(effects
							(font
								(size 1.016 1.016)
							)
						)
					)
				)
				(pin passive line
					(at 35.56 -17.78 180)
					(length 3.81)
					(name "DQ4_A"
						(effects
							(font
								(size 1.016 1.016)
							)
						)
					)
					(number "23"
						(effects
							(font
								(size 1.016 1.016)
							)
						)
					)
				)
				(pin passive line
					(at 35.56 -20.32 180)
					(length 3.81)
					(name "DQ5_A"
						(effects
							(font
								(size 1.016 1.016)
							)
						)
					)
					(number "26"
						(effects
							(font
								(size 1.016 1.016)
							)
						)
					)
				)
				(pin passive line
					(at 35.56 -22.86 180)
					(length 3.81)
					(name "DQ6_A"
						(effects
							(font
								(size 1.016 1.016)
							)
						)
					)
					(number "27"
						(effects
							(font
								(size 1.016 1.016)
							)
						)
					)
				)
				(pin passive line
					(at 35.56 -25.4 180)
					(length 3.81)
					(name "DQ7_A"
						(effects
							(font
								(size 1.016 1.016)
							)
						)
					)
					(number "30"
						(effects
							(font
								(size 1.016 1.016)
							)
						)
					)
				)
				(pin passive line
					(at 35.56 -30.48 180)
					(length 3.81)
					(name "DQS1_A_t"
						(effects
							(font
								(size 1.016 1.016)
							)
						)
					)
					(number "41"
						(effects
							(font
								(size 1.016 1.016)
							)
						)
					)
				)
				(pin passive line
					(at 35.56 -33.02 180)
					(length 3.81)
					(name "DQS1_A_C"
						(effects
							(font
								(size 1.016 1.016)
							)
						)
					)
					(number "39"
						(effects
							(font
								(size 1.016 1.016)
							)
						)
					)
				)
				(pin passive line
					(at 35.56 -38.1 180)
					(length 3.81)
					(name "DQ8_A"
						(effects
							(font
								(size 1.016 1.016)
							)
						)
					)
					(number "31"
						(effects
							(font
								(size 1.016 1.016)
							)
						)
					)
				)
				(pin passive line
					(at 35.56 -40.64 180)
					(length 3.81)
					(name "DQ09_A"
						(effects
							(font
								(size 1.016 1.016)
							)
						)
					)
					(number "34"
						(effects
							(font
								(size 1.016 1.016)
							)
						)
					)
				)
				(pin passive line
					(at 35.56 -43.18 180)
					(length 3.81)
					(name "DQ10_A"
						(effects
							(font
								(size 1.016 1.016)
							)
						)
					)
					(number "35"
						(effects
							(font
								(size 1.016 1.016)
							)
						)
					)
				)
				(pin passive line
					(at 35.56 -45.72 180)
					(length 3.81)
					(name "DQ11_A"
						(effects
							(font
								(size 1.016 1.016)
							)
						)
					)
					(number "38"
						(effects
							(font
								(size 1.016 1.016)
							)
						)
					)
				)
				(pin passive line
					(at 35.56 -48.26 180)
					(length 3.81)
					(name "DQ12_A"
						(effects
							(font
								(size 1.016 1.016)
							)
						)
					)
					(number "45"
						(effects
							(font
								(size 1.016 1.016)
							)
						)
					)
				)
				(pin passive line
					(at 35.56 -50.8 180)
					(length 3.81)
					(name "DQ13_A"
						(effects
							(font
								(size 1.016 1.016)
							)
						)
					)
					(number "46"
						(effects
							(font
								(size 1.016 1.016)
							)
						)
					)
				)
				(pin passive line
					(at 35.56 -53.34 180)
					(length 3.81)
					(name "DQ14_A"
						(effects
							(font
								(size 1.016 1.016)
							)
						)
					)
					(number "49"
						(effects
							(font
								(size 1.016 1.016)
							)
						)
					)
				)
				(pin passive line
					(at 35.56 -55.88 180)
					(length 3.81)
					(name "DQ15_A"
						(effects
							(font
								(size 1.016 1.016)
							)
						)
					)
					(number "50"
						(effects
							(font
								(size 1.016 1.016)
							)
						)
					)
				)
				(pin passive line
					(at 35.56 -60.96 180)
					(length 3.81)
					(name "DQS2_A_t"
						(effects
							(font
								(size 1.016 1.016)
							)
						)
					)
					(number "64"
						(effects
							(font
								(size 1.016 1.016)
							)
						)
					)
				)
				(pin passive line
					(at 35.56 -63.5 180)
					(length 3.81)
					(name "DQS2_A_C"
						(effects
							(font
								(size 1.016 1.016)
							)
						)
					)
					(number "62"
						(effects
							(font
								(size 1.016 1.016)
							)
						)
					)
				)
				(pin passive line
					(at 35.56 -68.58 180)
					(length 3.81)
					(name "DQ16_A"
						(effects
							(font
								(size 1.016 1.016)
							)
						)
					)
					(number "53"
						(effects
							(font
								(size 1.016 1.016)
							)
						)
					)
				)
				(pin passive line
					(at 35.56 -71.12 180)
					(length 3.81)
					(name "DQ17_A"
						(effects
							(font
								(size 1.016 1.016)
							)
						)
					)
					(number "54"
						(effects
							(font
								(size 1.016 1.016)
							)
						)
					)
				)
				(pin passive line
					(at 35.56 -73.66 180)
					(length 3.81)
					(name "DQ18_A"
						(effects
							(font
								(size 1.016 1.016)
							)
						)
					)
					(number "57"
						(effects
							(font
								(size 1.016 1.016)
							)
						)
					)
				)
				(pin passive line
					(at 35.56 -76.2 180)
					(length 3.81)
					(name "DQ19_A"
						(effects
							(font
								(size 1.016 1.016)
							)
						)
					)
					(number "58"
						(effects
							(font
								(size 1.016 1.016)
							)
						)
					)
				)
				(pin passive line
					(at 35.56 -78.74 180)
					(length 3.81)
					(name "DQ20_A"
						(effects
							(font
								(size 1.016 1.016)
							)
						)
					)
					(number "65"
						(effects
							(font
								(size 1.016 1.016)
							)
						)
					)
				)
				(pin passive line
					(at 35.56 -81.28 180)
					(length 3.81)
					(name "DQ21_A"
						(effects
							(font
								(size 1.016 1.016)
							)
						)
					)
					(number "68"
						(effects
							(font
								(size 1.016 1.016)
							)
						)
					)
				)
				(pin passive line
					(at 35.56 -83.82 180)
					(length 3.81)
					(name "DQ22_A"
						(effects
							(font
								(size 1.016 1.016)
							)
						)
					)
					(number "69"
						(effects
							(font
								(size 1.016 1.016)
							)
						)
					)
				)
				(pin passive line
					(at 35.56 -86.36 180)
					(length 3.81)
					(name "DQ23_A"
						(effects
							(font
								(size 1.016 1.016)
							)
						)
					)
					(number "72"
						(effects
							(font
								(size 1.016 1.016)
							)
						)
					)
				)
				(pin passive line
					(at 35.56 -91.44 180)
					(length 3.81)
					(name "DQS3_A_t"
						(effects
							(font
								(size 1.016 1.016)
							)
						)
					)
					(number "83"
						(effects
							(font
								(size 1.016 1.016)
							)
						)
					)
				)
				(pin passive line
					(at 35.56 -93.98 180)
					(length 3.81)
					(name "DQS3_A_C"
						(effects
							(font
								(size 1.016 1.016)
							)
						)
					)
					(number "81"
						(effects
							(font
								(size 1.016 1.016)
							)
						)
					)
				)
				(pin passive line
					(at 35.56 -99.06 180)
					(length 3.81)
					(name "DQ24_A"
						(effects
							(font
								(size 1.016 1.016)
							)
						)
					)
					(number "73"
						(effects
							(font
								(size 1.016 1.016)
							)
						)
					)
				)
				(pin passive line
					(at 35.56 -101.6 180)
					(length 3.81)
					(name "DQ25_A"
						(effects
							(font
								(size 1.016 1.016)
							)
						)
					)
					(number "76"
						(effects
							(font
								(size 1.016 1.016)
							)
						)
					)
				)
				(pin passive line
					(at 35.56 -104.14 180)
					(length 3.81)
					(name "DQ26_A"
						(effects
							(font
								(size 1.016 1.016)
							)
						)
					)
					(number "77"
						(effects
							(font
								(size 1.016 1.016)
							)
						)
					)
				)
				(pin passive line
					(at 35.56 -106.68 180)
					(length 3.81)
					(name "DQ27_A"
						(effects
							(font
								(size 1.016 1.016)
							)
						)
					)
					(number "80"
						(effects
							(font
								(size 1.016 1.016)
							)
						)
					)
				)
				(pin passive line
					(at 35.56 -109.22 180)
					(length 3.81)
					(name "DQ28_A"
						(effects
							(font
								(size 1.016 1.016)
							)
						)
					)
					(number "87"
						(effects
							(font
								(size 1.016 1.016)
							)
						)
					)
				)
				(pin passive line
					(at 35.56 -111.76 180)
					(length 3.81)
					(name "DQ29_A"
						(effects
							(font
								(size 1.016 1.016)
							)
						)
					)
					(number "88"
						(effects
							(font
								(size 1.016 1.016)
							)
						)
					)
				)
				(pin passive line
					(at 35.56 -114.3 180)
					(length 3.81)
					(name "DQ30_A"
						(effects
							(font
								(size 1.016 1.016)
							)
						)
					)
					(number "91"
						(effects
							(font
								(size 1.016 1.016)
							)
						)
					)
				)
				(pin passive line
					(at 35.56 -116.84 180)
					(length 3.81)
					(name "DQ31_A"
						(effects
							(font
								(size 1.016 1.016)
							)
						)
					)
					(number "92"
						(effects
							(font
								(size 1.016 1.016)
							)
						)
					)
				)
			)
			(symbol "PCB-Edge_SODIMM_2x131_LPDDR5_Testbed_2_1"
				(rectangle
					(start 3.81 2.54)
					(end 31.75 -119.38)
					(stroke
						(width 0)
						(type default)
					)
					(fill
						(type background)
					)
				)
				(polyline
					(pts
						(xy 10.16 -76.2) (xy 13.97 -76.2) (xy 13.97 -96.52) (xy 10.16 -96.52)
					)
					(stroke
						(width 0)
						(type default)
					)
					(fill
						(type none)
					)
				)
				(polyline
					(pts
						(xy 22.86 0) (xy 22.86 -25.4)
					)
					(stroke
						(width 0)
						(type default)
					)
					(fill
						(type none)
					)
				)
				(polyline
					(pts
						(xy 22.86 -30.48) (xy 22.86 -55.88)
					)
					(stroke
						(width 0)
						(type default)
					)
					(fill
						(type none)
					)
				)
				(polyline
					(pts
						(xy 22.86 -60.96) (xy 22.86 -86.36)
					)
					(stroke
						(width 0)
						(type default)
					)
					(fill
						(type none)
					)
				)
				(polyline
					(pts
						(xy 22.86 -91.44) (xy 22.86 -116.84)
					)
					(stroke
						(width 0)
						(type default)
					)
					(fill
						(type none)
					)
				)
				(text "ECC"
					(at 12.7 -86.36 900)
					(effects
						(font
							(size 1.27 1.27)
						)
					)
				)
			)
			(symbol "PCB-Edge_SODIMM_2x131_LPDDR5_Testbed_3_0"
				(pin passive line
					(at 0 0 0)
					(length 3.81)
					(name "CS0_B_n"
						(effects
							(font
								(size 1.016 1.016)
							)
						)
					)
					(number "161"
						(effects
							(font
								(size 1.016 1.016)
							)
						)
					)
				)
				(pin passive line
					(at 0 -2.54 0)
					(length 3.81)
					(name "CS1_B_N"
						(effects
							(font
								(size 1.016 1.016)
							)
						)
					)
					(number "165"
						(effects
							(font
								(size 1.016 1.016)
							)
						)
					)
				)
				(pin passive line
					(at 0 -10.16 0)
					(length 3.81)
					(name "DM0_B_n"
						(effects
							(font
								(size 1.016 1.016)
							)
						)
					)
					(number "187"
						(effects
							(font
								(size 1.016 1.016)
							)
						)
					)
				)
				(pin passive line
					(at 0 -12.7 0)
					(length 3.81)
					(name "DM1_B_n"
						(effects
							(font
								(size 1.016 1.016)
							)
						)
					)
					(number "210"
						(effects
							(font
								(size 1.016 1.016)
							)
						)
					)
				)
				(pin passive line
					(at 0 -15.24 0)
					(length 3.81)
					(name "DM2_B_n"
						(effects
							(font
								(size 1.016 1.016)
							)
						)
					)
					(number "229"
						(effects
							(font
								(size 1.016 1.016)
							)
						)
					)
				)
				(pin passive line
					(at 0 -17.78 0)
					(length 3.81)
					(name "DM3_B_n"
						(effects
							(font
								(size 1.016 1.016)
							)
						)
					)
					(number "252"
						(effects
							(font
								(size 1.016 1.016)
							)
						)
					)
				)
				(pin passive line
					(at 0 -25.4 0)
					(length 3.81)
					(name "CK0_B_t"
						(effects
							(font
								(size 1.016 1.016)
							)
						)
					)
					(number "137"
						(effects
							(font
								(size 1.016 1.016)
							)
						)
					)
				)
				(pin passive line
					(at 0 -27.94 0)
					(length 3.81)
					(name "CK0_B_c"
						(effects
							(font
								(size 1.016 1.016)
							)
						)
					)
					(number "139"
						(effects
							(font
								(size 1.016 1.016)
							)
						)
					)
				)
				(pin passive line
					(at 0 -33.02 0)
					(length 3.81)
					(name "CK1_B_t"
						(effects
							(font
								(size 1.016 1.016)
							)
						)
					)
					(number "138"
						(effects
							(font
								(size 1.016 1.016)
							)
						)
					)
				)
				(pin passive line
					(at 0 -35.56 0)
					(length 3.81)
					(name "CK1_B_C"
						(effects
							(font
								(size 1.016 1.016)
							)
						)
					)
					(number "140"
						(effects
							(font
								(size 1.016 1.016)
							)
						)
					)
				)
				(pin passive line
					(at 0 -40.64 0)
					(length 3.81)
					(name "CA0_B"
						(effects
							(font
								(size 1.016 1.016)
							)
						)
					)
					(number "164"
						(effects
							(font
								(size 1.016 1.016)
							)
						)
					)
				)
				(pin passive line
					(at 0 -43.18 0)
					(length 3.81)
					(name "CA1_B"
						(effects
							(font
								(size 1.016 1.016)
							)
						)
					)
					(number "162"
						(effects
							(font
								(size 1.016 1.016)
							)
						)
					)
				)
				(pin passive line
					(at 0 -45.72 0)
					(length 3.81)
					(name "CA2_B"
						(effects
							(font
								(size 1.016 1.016)
							)
						)
					)
					(number "158"
						(effects
							(font
								(size 1.016 1.016)
							)
						)
					)
				)
				(pin passive line
					(at 0 -48.26 0)
					(length 3.81)
					(name "CA3_B"
						(effects
							(font
								(size 1.016 1.016)
							)
						)
					)
					(number "157"
						(effects
							(font
								(size 1.016 1.016)
							)
						)
					)
				)
				(pin passive line
					(at 0 -50.8 0)
					(length 3.81)
					(name "CA4_B"
						(effects
							(font
								(size 1.016 1.016)
							)
						)
					)
					(number "156"
						(effects
							(font
								(size 1.016 1.016)
							)
						)
					)
				)
				(pin passive line
					(at 0 -53.34 0)
					(length 3.81)
					(name "CA5_B"
						(effects
							(font
								(size 1.016 1.016)
							)
						)
					)
					(number "155"
						(effects
							(font
								(size 1.016 1.016)
							)
						)
					)
				)
				(pin passive line
					(at 0 -55.88 0)
					(length 3.81)
					(name "CA6_B"
						(effects
							(font
								(size 1.016 1.016)
							)
						)
					)
					(number "152"
						(effects
							(font
								(size 1.016 1.016)
							)
						)
					)
				)
				(pin passive line
					(at 0 -58.42 0)
					(length 3.81)
					(name "CA7_B"
						(effects
							(font
								(size 1.016 1.016)
							)
						)
					)
					(number "151"
						(effects
							(font
								(size 1.016 1.016)
							)
						)
					)
				)
				(pin passive line
					(at 0 -60.96 0)
					(length 3.81)
					(name "CA8_B"
						(effects
							(font
								(size 1.016 1.016)
							)
						)
					)
					(number "150"
						(effects
							(font
								(size 1.016 1.016)
							)
						)
					)
				)
				(pin passive line
					(at 0 -63.5 0)
					(length 3.81)
					(name "CA9_B"
						(effects
							(font
								(size 1.016 1.016)
							)
						)
					)
					(number "149"
						(effects
							(font
								(size 1.016 1.016)
							)
						)
					)
				)
				(pin passive line
					(at 0 -66.04 0)
					(length 3.81)
					(name "CA10_B"
						(effects
							(font
								(size 1.016 1.016)
							)
						)
					)
					(number "146"
						(effects
							(font
								(size 1.016 1.016)
							)
						)
					)
				)
				(pin passive line
					(at 0 -68.58 0)
					(length 3.81)
					(name "CA11_B"
						(effects
							(font
								(size 1.016 1.016)
							)
						)
					)
					(number "145"
						(effects
							(font
								(size 1.016 1.016)
							)
						)
					)
				)
				(pin passive line
					(at 0 -71.12 0)
					(length 3.81)
					(name "CA12_B"
						(effects
							(font
								(size 1.016 1.016)
							)
						)
					)
					(number "144"
						(effects
							(font
								(size 1.016 1.016)
							)
						)
					)
				)
				(pin passive line
					(at 0 -78.74 0)
					(length 3.81)
					(name "DQS4_B_T"
						(effects
							(font
								(size 1.016 1.016)
							)
						)
					)
					(number "171"
						(effects
							(font
								(size 1.016 1.016)
							)
						)
					)
				)
				(pin passive line
					(at 0 -81.28 0)
					(length 3.81)
					(name "DQS4_B_c"
						(effects
							(font
								(size 1.016 1.016)
							)
						)
					)
					(number "169"
						(effects
							(font
								(size 1.016 1.016)
							)
						)
					)
				)
				(pin passive line
					(at 0 -86.36 0)
					(length 3.81)
					(name "CB0_B"
						(effects
							(font
								(size 1.016 1.016)
							)
						)
					)
					(number "168"
						(effects
							(font
								(size 1.016 1.016)
							)
						)
					)
				)
				(pin passive line
					(at 0 -88.9 0)
					(length 3.81)
					(name "CB1_B"
						(effects
							(font
								(size 1.016 1.016)
							)
						)
					)
					(number "172"
						(effects
							(font
								(size 1.016 1.016)
							)
						)
					)
				)
				(pin passive line
					(at 0 -91.44 0)
					(length 3.81)
					(name "CB2_B"
						(effects
							(font
								(size 1.016 1.016)
							)
						)
					)
					(number "176"
						(effects
							(font
								(size 1.016 1.016)
							)
						)
					)
				)
				(pin passive line
					(at 0 -93.98 0)
					(length 3.81)
					(name "CB3_B"
						(effects
							(font
								(size 1.016 1.016)
							)
						)
					)
					(number "175"
						(effects
							(font
								(size 1.016 1.016)
							)
						)
					)
				)
				(pin passive line
					(at 35.56 0 180)
					(length 3.81)
					(name "DQS0_B_t"
						(effects
							(font
								(size 1.016 1.016)
							)
						)
					)
					(number "190"
						(effects
							(font
								(size 1.016 1.016)
							)
						)
					)
				)
				(pin passive line
					(at 35.56 -2.54 180)
					(length 3.81)
					(name "DQS0_B_C"
						(effects
							(font
								(size 1.016 1.016)
							)
						)
					)
					(number "188"
						(effects
							(font
								(size 1.016 1.016)
							)
						)
					)
				)
				(pin passive line
					(at 35.56 -7.62 180)
					(length 3.81)
					(name "DQ0_B"
						(effects
							(font
								(size 1.016 1.016)
							)
						)
					)
					(number "179"
						(effects
							(font
								(size 1.016 1.016)
							)
						)
					)
				)
				(pin passive line
					(at 35.56 -10.16 180)
					(length 3.81)
					(name "DQ1_B"
						(effects
							(font
								(size 1.016 1.016)
							)
						)
					)
					(number "180"
						(effects
							(font
								(size 1.016 1.016)
							)
						)
					)
				)
				(pin passive line
					(at 35.56 -12.7 180)
					(length 3.81)
					(name "DQ2_B"
						(effects
							(font
								(size 1.016 1.016)
							)
						)
					)
					(number "183"
						(effects
							(font
								(size 1.016 1.016)
							)
						)
					)
				)
				(pin passive line
					(at 35.56 -15.24 180)
					(length 3.81)
					(name "DQ3_B"
						(effects
							(font
								(size 1.016 1.016)
							)
						)
					)
					(number "184"
						(effects
							(font
								(size 1.016 1.016)
							)
						)
					)
				)
				(pin passive line
					(at 35.56 -17.78 180)
					(length 3.81)
					(name "DQ4_B"
						(effects
							(font
								(size 1.016 1.016)
							)
						)
					)
					(number "191"
						(effects
							(font
								(size 1.016 1.016)
							)
						)
					)
				)
				(pin passive line
					(at 35.56 -20.32 180)
					(length 3.81)
					(name "DQ5_B"
						(effects
							(font
								(size 1.016 1.016)
							)
						)
					)
					(number "194"
						(effects
							(font
								(size 1.016 1.016)
							)
						)
					)
				)
				(pin passive line
					(at 35.56 -22.86 180)
					(length 3.81)
					(name "DQ6_B"
						(effects
							(font
								(size 1.016 1.016)
							)
						)
					)
					(number "195"
						(effects
							(font
								(size 1.016 1.016)
							)
						)
					)
				)
				(pin passive line
					(at 35.56 -25.4 180)
					(length 3.81)
					(name "DQ7_B"
						(effects
							(font
								(size 1.016 1.016)
							)
						)
					)
					(number "198"
						(effects
							(font
								(size 1.016 1.016)
							)
						)
					)
				)
				(pin passive line
					(at 35.56 -30.48 180)
					(length 3.81)
					(name "DQS1_B_t"
						(effects
							(font
								(size 1.016 1.016)
							)
						)
					)
					(number "209"
						(effects
							(font
								(size 1.016 1.016)
							)
						)
					)
				)
				(pin passive line
					(at 35.56 -33.02 180)
					(length 3.81)
					(name "DQS1_B_C"
						(effects
							(font
								(size 1.016 1.016)
							)
						)
					)
					(number "207"
						(effects
							(font
								(size 1.016 1.016)
							)
						)
					)
				)
				(pin passive line
					(at 35.56 -38.1 180)
					(length 3.81)
					(name "DQ8_B"
						(effects
							(font
								(size 1.016 1.016)
							)
						)
					)
					(number "199"
						(effects
							(font
								(size 1.016 1.016)
							)
						)
					)
				)
				(pin passive line
					(at 35.56 -40.64 180)
					(length 3.81)
					(name "DQ9_B"
						(effects
							(font
								(size 1.016 1.016)
							)
						)
					)
					(number "202"
						(effects
							(font
								(size 1.016 1.016)
							)
						)
					)
				)
				(pin passive line
					(at 35.56 -43.18 180)
					(length 3.81)
					(name "DQ10_B"
						(effects
							(font
								(size 1.016 1.016)
							)
						)
					)
					(number "203"
						(effects
							(font
								(size 1.016 1.016)
							)
						)
					)
				)
				(pin passive line
					(at 35.56 -45.72 180)
					(length 3.81)
					(name "DQ11_B"
						(effects
							(font
								(size 1.016 1.016)
							)
						)
					)
					(number "206"
						(effects
							(font
								(size 1.016 1.016)
							)
						)
					)
				)
				(pin passive line
					(at 35.56 -48.26 180)
					(length 3.81)
					(name "DQ12_B"
						(effects
							(font
								(size 1.016 1.016)
							)
						)
					)
					(number "213"
						(effects
							(font
								(size 1.016 1.016)
							)
						)
					)
				)
				(pin passive line
					(at 35.56 -50.8 180)
					(length 3.81)
					(name "DQ13_B"
						(effects
							(font
								(size 1.016 1.016)
							)
						)
					)
					(number "214"
						(effects
							(font
								(size 1.016 1.016)
							)
						)
					)
				)
				(pin passive line
					(at 35.56 -53.34 180)
					(length 3.81)
					(name "DQ14_B"
						(effects
							(font
								(size 1.016 1.016)
							)
						)
					)
					(number "217"
						(effects
							(font
								(size 1.016 1.016)
							)
						)
					)
				)
				(pin passive line
					(at 35.56 -55.88 180)
					(length 3.81)
					(name "DQ15_B"
						(effects
							(font
								(size 1.016 1.016)
							)
						)
					)
					(number "218"
						(effects
							(font
								(size 1.016 1.016)
							)
						)
					)
				)
				(pin passive line
					(at 35.56 -60.96 180)
					(length 3.81)
					(name "DQS2_B_t"
						(effects
							(font
								(size 1.016 1.016)
							)
						)
					)
					(number "232"
						(effects
							(font
								(size 1.016 1.016)
							)
						)
					)
				)
				(pin passive line
					(at 35.56 -63.5 180)
					(length 3.81)
					(name "DQS2_B_C"
						(effects
							(font
								(size 1.016 1.016)
							)
						)
					)
					(number "230"
						(effects
							(font
								(size 1.016 1.016)
							)
						)
					)
				)
				(pin passive line
					(at 35.56 -68.58 180)
					(length 3.81)
					(name "DQ16_B"
						(effects
							(font
								(size 1.016 1.016)
							)
						)
					)
					(number "221"
						(effects
							(font
								(size 1.016 1.016)
							)
						)
					)
				)
				(pin passive line
					(at 35.56 -71.12 180)
					(length 3.81)
					(name "DQ17_B"
						(effects
							(font
								(size 1.016 1.016)
							)
						)
					)
					(number "222"
						(effects
							(font
								(size 1.016 1.016)
							)
						)
					)
				)
				(pin passive line
					(at 35.56 -73.66 180)
					(length 3.81)
					(name "DQ18_B"
						(effects
							(font
								(size 1.016 1.016)
							)
						)
					)
					(number "225"
						(effects
							(font
								(size 1.016 1.016)
							)
						)
					)
				)
				(pin passive line
					(at 35.56 -76.2 180)
					(length 3.81)
					(name "DQ19_B"
						(effects
							(font
								(size 1.016 1.016)
							)
						)
					)
					(number "226"
						(effects
							(font
								(size 1.016 1.016)
							)
						)
					)
				)
				(pin passive line
					(at 35.56 -78.74 180)
					(length 3.81)
					(name "DQ20_B"
						(effects
							(font
								(size 1.016 1.016)
							)
						)
					)
					(number "233"
						(effects
							(font
								(size 1.016 1.016)
							)
						)
					)
				)
				(pin passive line
					(at 35.56 -81.28 180)
					(length 3.81)
					(name "DQ21_B"
						(effects
							(font
								(size 1.016 1.016)
							)
						)
					)
					(number "236"
						(effects
							(font
								(size 1.016 1.016)
							)
						)
					)
				)
				(pin passive line
					(at 35.56 -83.82 180)
					(length 3.81)
					(name "DQ22_B"
						(effects
							(font
								(size 1.016 1.016)
							)
						)
					)
					(number "237"
						(effects
							(font
								(size 1.016 1.016)
							)
						)
					)
				)
				(pin passive line
					(at 35.56 -86.36 180)
					(length 3.81)
					(name "DQ23_B"
						(effects
							(font
								(size 1.016 1.016)
							)
						)
					)
					(number "240"
						(effects
							(font
								(size 1.016 1.016)
							)
						)
					)
				)
				(pin passive line
					(at 35.56 -91.44 180)
					(length 3.81)
					(name "DQS3_B_t"
						(effects
							(font
								(size 1.016 1.016)
							)
						)
					)
					(number "251"
						(effects
							(font
								(size 1.016 1.016)
							)
						)
					)
				)
				(pin passive line
					(at 35.56 -93.98 180)
					(length 3.81)
					(name "DQS3_B_c"
						(effects
							(font
								(size 1.016 1.016)
							)
						)
					)
					(number "249"
						(effects
							(font
								(size 1.016 1.016)
							)
						)
					)
				)
				(pin passive line
					(at 35.56 -99.06 180)
					(length 3.81)
					(name "DQ24_B"
						(effects
							(font
								(size 1.016 1.016)
							)
						)
					)
					(number "241"
						(effects
							(font
								(size 1.016 1.016)
							)
						)
					)
				)
				(pin passive line
					(at 35.56 -101.6 180)
					(length 3.81)
					(name "DQ25_B"
						(effects
							(font
								(size 1.016 1.016)
							)
						)
					)
					(number "244"
						(effects
							(font
								(size 1.016 1.016)
							)
						)
					)
				)
				(pin passive line
					(at 35.56 -104.14 180)
					(length 3.81)
					(name "DQ26_B"
						(effects
							(font
								(size 1.016 1.016)
							)
						)
					)
					(number "245"
						(effects
							(font
								(size 1.016 1.016)
							)
						)
					)
				)
				(pin passive line
					(at 35.56 -106.68 180)
					(length 3.81)
					(name "DQ27_B"
						(effects
							(font
								(size 1.016 1.016)
							)
						)
					)
					(number "248"
						(effects
							(font
								(size 1.016 1.016)
							)
						)
					)
				)
				(pin passive line
					(at 35.56 -109.22 180)
					(length 3.81)
					(name "DQ28_B"
						(effects
							(font
								(size 1.016 1.016)
							)
						)
					)
					(number "255"
						(effects
							(font
								(size 1.016 1.016)
							)
						)
					)
				)
				(pin passive line
					(at 35.56 -111.76 180)
					(length 3.81)
					(name "DQ29_B"
						(effects
							(font
								(size 1.016 1.016)
							)
						)
					)
					(number "256"
						(effects
							(font
								(size 1.016 1.016)
							)
						)
					)
				)
				(pin passive line
					(at 35.56 -114.3 180)
					(length 3.81)
					(name "DQ30_B"
						(effects
							(font
								(size 1.016 1.016)
							)
						)
					)
					(number "259"
						(effects
							(font
								(size 1.016 1.016)
							)
						)
					)
				)
				(pin passive line
					(at 35.56 -116.84 180)
					(length 3.81)
					(name "DQ31_B"
						(effects
							(font
								(size 1.016 1.016)
							)
						)
					)
					(number "260"
						(effects
							(font
								(size 1.016 1.016)
							)
						)
					)
				)
			)
			(symbol "PCB-Edge_SODIMM_2x131_LPDDR5_Testbed_3_1"
				(rectangle
					(start 3.81 2.54)
					(end 31.75 -119.38)
					(stroke
						(width 0)
						(type default)
					)
					(fill
						(type background)
					)
				)
				(polyline
					(pts
						(xy 10.16 -76.2) (xy 13.97 -76.2) (xy 13.97 -96.52) (xy 10.16 -96.52)
					)
					(stroke
						(width 0)
						(type default)
					)
					(fill
						(type none)
					)
				)
				(polyline
					(pts
						(xy 22.86 0) (xy 22.86 -25.4)
					)
					(stroke
						(width 0)
						(type default)
					)
					(fill
						(type none)
					)
				)
				(polyline
					(pts
						(xy 22.86 -30.48) (xy 22.86 -55.88)
					)
					(stroke
						(width 0)
						(type default)
					)
					(fill
						(type none)
					)
				)
				(polyline
					(pts
						(xy 22.86 -60.96) (xy 22.86 -86.36)
					)
					(stroke
						(width 0)
						(type default)
					)
					(fill
						(type none)
					)
				)
				(polyline
					(pts
						(xy 22.86 -91.44) (xy 22.86 -116.84)
					)
					(stroke
						(width 0)
						(type default)
					)
					(fill
						(type none)
					)
				)
				(text "ECC"
					(at 12.7 -86.36 900)
					(effects
						(font
							(size 1.27 1.27)
						)
					)
				)
			)
		)
	(symbol "antmicroLEDIndicationDiscrete:LED_G_0603_KP-1608CGCK"
			(pin_names
				(hide yes)
			)
			(exclude_from_sim no)
			(in_bom yes)
			(on_board yes)
			(property "Reference" "D"
				(at 22.86 -5.08 0)
				(effects
					(font
						(size 1.27 1.27)
						(thickness 0.15)
					)
					(justify left bottom)
				)
			)
			(property "Value" "LED_G_0603_KP-1608CGCK"
				(at 22.86 -7.62 0)
				(effects
					(font
						(size 1.27 1.27)
						(thickness 0.15)
					)
					(justify left bottom)
				)
			)
			(property "Footprint" "antmicro-footprints:LED_0603_1608Metric_G"
				(at 22.86 -10.16 0)
				(effects
					(font
						(size 1.27 1.27)
						(thickness 0.15)
					)
					(justify left bottom)
					(hide yes)
				)
			)
			(property "Datasheet" "http://www.farnell.com/datasheets/2045956.pdf"
				(at 22.86 -12.7 0)
				(effects
					(font
						(size 1.27 1.27)
						(thickness 0.15)
					)
					(justify left bottom)
					(hide yes)
				)
			)
			(property "Description" "LED, Low Power, Green, SMT, 0603, 20 mA, 2.1 V, 570 nm"
				(at 0 0 0)
				(effects
					(font
						(size 1.27 1.27)
					)
					(hide yes)
				)
			)
			(property "MPN" "KP-1608CGCK"
				(at 22.86 -15.24 0)
				(effects
					(font
						(size 1.27 1.27)
						(thickness 0.15)
					)
					(justify left bottom)
					(hide yes)
				)
			)
			(property "Manufacturer" "Kingbright"
				(at 22.86 -17.78 0)
				(effects
					(font
						(size 1.27 1.27)
						(thickness 0.15)
					)
					(justify left bottom)
					(hide yes)
				)
			)
			(property "Author" "Antmicro"
				(at 22.86 -20.32 0)
				(effects
					(font
						(size 1.27 1.27)
						(thickness 0.15)
					)
					(justify left bottom)
					(hide yes)
				)
			)
			(property "License" "Apache-2.0"
				(at 22.86 -22.86 0)
				(effects
					(font
						(size 1.27 1.27)
						(thickness 0.15)
					)
					(justify left bottom)
					(hide yes)
				)
			)
			(property "ki_keywords" "0603, SMT, LED, SEMICONDUCTOR"
				(at 0 0 0)
				(effects
					(font
						(size 1.27 1.27)
					)
					(hide yes)
				)
			)
			(symbol "LED_G_0603_KP-1608CGCK_1_1"
				(polyline
					(pts
						(xy 2.54 1.27) (xy 2.54 -1.27) (xy 5.08 0) (xy 2.54 1.27)
					)
					(stroke
						(width 0.254)
						(type default)
					)
					(fill
						(type outline)
					)
				)
				(polyline
					(pts
						(xy 3.683 2.286) (xy 3.683 1.778) (xy 3.683 2.286) (xy 3.175 2.286) (xy 3.683 2.286) (xy 2.794 1.397)
					)
					(stroke
						(width 0.254)
						(type default)
					)
					(fill
						(type none)
					)
				)
				(polyline
					(pts
						(xy 4.699 2.032) (xy 4.699 1.524) (xy 4.699 2.032) (xy 4.191 2.032) (xy 4.699 2.032) (xy 3.683 1.016)
					)
					(stroke
						(width 0.254)
						(type default)
					)
					(fill
						(type none)
					)
				)
				(polyline
					(pts
						(xy 5.08 1.27) (xy 5.08 -1.27)
					)
					(stroke
						(width 0.254)
						(type default)
					)
					(fill
						(type none)
					)
				)
				(pin passive line
					(at 0 0 0)
					(length 2.54)
					(name "1"
						(effects
							(font
								(size 1.27 1.27)
							)
						)
					)
					(number "1"
						(effects
							(font
								(size 1.27 1.27)
							)
						)
					)
				)
				(pin passive line
					(at 7.62 0 180)
					(length 2.54)
					(name "2"
						(effects
							(font
								(size 1.27 1.27)
							)
						)
					)
					(number "2"
						(effects
							(font
								(size 1.27 1.27)
							)
						)
					)
				)
			)
		)
	(symbol "antmicroMemory:AT24CS01_SOT23"
			(exclude_from_sim no)
			(in_bom yes)
			(on_board yes)
			(property "Reference" "U"
				(at 35.56 -2.54 0)
				(effects
					(font
						(size 1.27 1.27)
						(thickness 0.15)
					)
					(justify left bottom)
				)
			)
			(property "Value" "AT24CS01_SOT23"
				(at 35.56 -5.08 0)
				(effects
					(font
						(size 1.27 1.27)
						(thickness 0.15)
					)
					(justify left bottom)
				)
			)
			(property "Footprint" "antmicro-footprints:SOT-23-5"
				(at 35.56 -7.62 0)
				(effects
					(font
						(size 1.27 1.27)
						(thickness 0.15)
					)
					(justify left bottom)
					(hide yes)
				)
			)
			(property "Datasheet" "http://ww1.microchip.com/downloads/en/devicedoc/Atmel-8815-SEEPROM-AT24CS01-02-Datasheet.pdf"
				(at 35.56 -10.16 0)
				(effects
					(font
						(size 1.27 1.27)
						(thickness 0.15)
					)
					(justify left bottom)
					(hide yes)
				)
			)
			(property "Description" "EEPROM Memory IC 1Kbit I²C 1 MHz 550 ns SOT-23-5"
				(at 0 0 0)
				(effects
					(font
						(size 1.27 1.27)
					)
					(hide yes)
				)
			)
			(property "Manufacturer" "Atmel"
				(at 35.56 -12.7 0)
				(effects
					(font
						(size 1.27 1.27)
						(thickness 0.15)
					)
					(justify left bottom)
					(hide yes)
				)
			)
			(property "MPN" "AT24CS01-ST"
				(at 35.56 -15.24 0)
				(effects
					(font
						(size 1.27 1.27)
						(thickness 0.15)
					)
					(justify left bottom)
					(hide yes)
				)
			)
			(property "Author" "Antmicro"
				(at 35.56 -17.78 0)
				(effects
					(font
						(size 1.27 1.27)
						(thickness 0.15)
					)
					(justify left bottom)
					(hide yes)
				)
			)
			(property "License" "Apache-2.0"
				(at 35.56 -20.32 0)
				(effects
					(font
						(size 1.27 1.27)
						(thickness 0.15)
					)
					(justify left bottom)
					(hide yes)
				)
			)
			(property "ki_keywords" "IC"
				(at 0 0 0)
				(effects
					(font
						(size 1.27 1.27)
					)
					(hide yes)
				)
			)
			(symbol "AT24CS01_SOT23_1_1"
				(rectangle
					(start 2.54 -7.62)
					(end 17.78 2.54)
					(stroke
						(width 0.254)
						(type default)
					)
					(fill
						(type background)
					)
				)
				(pin passive line
					(at 0 0 0)
					(length 2.54)
					(name "SDA"
						(effects
							(font
								(size 1.27 1.27)
							)
						)
					)
					(number "3"
						(effects
							(font
								(size 1.27 1.27)
							)
						)
					)
				)
				(pin passive line
					(at 0 -2.54 0)
					(length 2.54)
					(name "SCL"
						(effects
							(font
								(size 1.27 1.27)
							)
						)
					)
					(number "1"
						(effects
							(font
								(size 1.27 1.27)
							)
						)
					)
				)
				(pin passive line
					(at 0 -5.08 0)
					(length 2.54)
					(name "WP"
						(effects
							(font
								(size 1.27 1.27)
							)
						)
					)
					(number "5"
						(effects
							(font
								(size 1.27 1.27)
							)
						)
					)
				)
				(pin passive line
					(at 20.32 0 180)
					(length 2.54)
					(name "VCC"
						(effects
							(font
								(size 1.27 1.27)
							)
						)
					)
					(number "4"
						(effects
							(font
								(size 1.27 1.27)
							)
						)
					)
				)
				(pin passive line
					(at 20.32 -2.54 180)
					(length 2.54)
					(name "GND"
						(effects
							(font
								(size 1.27 1.27)
							)
						)
					)
					(number "2"
						(effects
							(font
								(size 1.27 1.27)
							)
						)
					)
				)
			)
		)
	(symbol "antmicroMemory:MT62F1G32D4DR-031"
			(exclude_from_sim no)
			(in_bom yes)
			(on_board yes)
			(property "Reference" "U"
				(at 44.45 0 0)
				(effects
					(font
						(size 1.27 1.27)
					)
					(justify left bottom)
				)
			)
			(property "Value" "MT62F1G32D4DR-031"
				(at 44.45 -5.08 0)
				(effects
					(font
						(size 1.27 1.27)
					)
					(justify left bottom)
					(hide yes)
				)
			)
			(property "Footprint" "antmicro-footprints:BGA-315_12.4x15mm_Layout15x21_P0.8x0.7mm"
				(at 44.45 -12.7 0)
				(effects
					(font
						(size 1.27 1.27)
					)
					(justify left bottom)
					(hide yes)
				)
			)
			(property "Datasheet" "https://www.micron.com/search-results?searchRequest=%7B%22term%22%3A%22MT62F1G32D4DR-031%22%7D"
				(at 44.45 -10.16 0)
				(effects
					(font
						(size 1.27 1.27)
					)
					(justify left bottom)
					(hide yes)
				)
			)
			(property "Description" "DRAM LPDDR5 32G X32 TFBGA"
				(at 0 0 0)
				(effects
					(font
						(size 1.27 1.27)
					)
					(hide yes)
				)
			)
			(property "Manufacturer" "Micron Technology"
				(at 44.45 -7.62 0)
				(effects
					(font
						(size 1.27 1.27)
					)
					(justify left bottom)
					(hide yes)
				)
			)
			(property "MPN" "MT62F1G32D4DR-031 WT:B"
				(at 44.45 -2.54 0)
				(effects
					(font
						(size 1.27 1.27)
					)
					(justify left bottom)
				)
			)
			(property "Author" "Antmicro"
				(at 44.45 -15.24 0)
				(effects
					(font
						(size 1.27 1.27)
					)
					(justify left bottom)
					(hide yes)
				)
			)
			(property "License" "Apache-2.0"
				(at 44.45 -17.78 0)
				(effects
					(font
						(size 1.27 1.27)
					)
					(justify left bottom)
					(hide yes)
				)
			)
			(property "ki_locked" ""
				(at 0 0 0)
				(effects
					(font
						(size 1.27 1.27)
					)
				)
			)
			(property "ki_keywords" "BGA, DDR, MEMORY, DRAM"
				(at 0 0 0)
				(effects
					(font
						(size 1.27 1.27)
					)
					(hide yes)
				)
			)
			(symbol "MT62F1G32D4DR-031_1_0"
				(pin passive line
					(at 0 0 0)
					(length 5.08)
					(name "RESET_n"
						(effects
							(font
								(size 1.27 1.27)
							)
						)
					)
					(number "H1"
						(effects
							(font
								(size 1.27 1.27)
							)
						)
					)
				)
				(pin passive line
					(at 0 -6.35 0)
					(length 5.08)
					(name "VDD1"
						(effects
							(font
								(size 1.27 1.27)
							)
						)
					)
					(number "C1"
						(effects
							(font
								(size 1.27 1.27)
							)
						)
					)
				)
				(pin passive line
					(at 0 -6.35 0)
					(length 5.08)
					(hide yes)
					(name "VDD1"
						(effects
							(font
								(size 1.27 1.27)
							)
						)
					)
					(number "C15"
						(effects
							(font
								(size 1.27 1.27)
							)
						)
					)
				)
				(pin passive line
					(at 0 -6.35 0)
					(length 5.08)
					(hide yes)
					(name "VDD1"
						(effects
							(font
								(size 1.27 1.27)
							)
						)
					)
					(number "W1"
						(effects
							(font
								(size 1.27 1.27)
							)
						)
					)
				)
				(pin passive line
					(at 0 -6.35 0)
					(length 5.08)
					(hide yes)
					(name "VDD1"
						(effects
							(font
								(size 1.27 1.27)
							)
						)
					)
					(number "W15"
						(effects
							(font
								(size 1.27 1.27)
							)
						)
					)
				)
				(pin passive line
					(at 0 -13.97 0)
					(length 5.08)
					(hide yes)
					(name "VDDQ"
						(effects
							(font
								(size 1.27 1.27)
							)
						)
					)
					(number "A13"
						(effects
							(font
								(size 1.27 1.27)
							)
						)
					)
				)
				(pin passive line
					(at 0 -13.97 0)
					(length 5.08)
					(name "VDDQ"
						(effects
							(font
								(size 1.27 1.27)
							)
						)
					)
					(number "A3"
						(effects
							(font
								(size 1.27 1.27)
							)
						)
					)
				)
				(pin passive line
					(at 0 -13.97 0)
					(length 5.08)
					(hide yes)
					(name "VDDQ"
						(effects
							(font
								(size 1.27 1.27)
							)
						)
					)
					(number "AA13"
						(effects
							(font
								(size 1.27 1.27)
							)
						)
					)
				)
				(pin passive line
					(at 0 -13.97 0)
					(length 5.08)
					(hide yes)
					(name "VDDQ"
						(effects
							(font
								(size 1.27 1.27)
							)
						)
					)
					(number "AA3"
						(effects
							(font
								(size 1.27 1.27)
							)
						)
					)
				)
				(pin passive line
					(at 0 -13.97 0)
					(length 5.08)
					(hide yes)
					(name "VDDQ"
						(effects
							(font
								(size 1.27 1.27)
							)
						)
					)
					(number "B14"
						(effects
							(font
								(size 1.27 1.27)
							)
						)
					)
				)
				(pin passive line
					(at 0 -13.97 0)
					(length 5.08)
					(hide yes)
					(name "VDDQ"
						(effects
							(font
								(size 1.27 1.27)
							)
						)
					)
					(number "B2"
						(effects
							(font
								(size 1.27 1.27)
							)
						)
					)
				)
				(pin passive line
					(at 0 -13.97 0)
					(length 5.08)
					(hide yes)
					(name "VDDQ"
						(effects
							(font
								(size 1.27 1.27)
							)
						)
					)
					(number "C13"
						(effects
							(font
								(size 1.27 1.27)
							)
						)
					)
				)
				(pin passive line
					(at 0 -13.97 0)
					(length 5.08)
					(hide yes)
					(name "VDDQ"
						(effects
							(font
								(size 1.27 1.27)
							)
						)
					)
					(number "C3"
						(effects
							(font
								(size 1.27 1.27)
							)
						)
					)
				)
				(pin passive line
					(at 0 -13.97 0)
					(length 5.08)
					(hide yes)
					(name "VDDQ"
						(effects
							(font
								(size 1.27 1.27)
							)
						)
					)
					(number "D12"
						(effects
							(font
								(size 1.27 1.27)
							)
						)
					)
				)
				(pin passive line
					(at 0 -13.97 0)
					(length 5.08)
					(hide yes)
					(name "VDDQ"
						(effects
							(font
								(size 1.27 1.27)
							)
						)
					)
					(number "D4"
						(effects
							(font
								(size 1.27 1.27)
							)
						)
					)
				)
				(pin passive line
					(at 0 -13.97 0)
					(length 5.08)
					(hide yes)
					(name "VDDQ"
						(effects
							(font
								(size 1.27 1.27)
							)
						)
					)
					(number "E11"
						(effects
							(font
								(size 1.27 1.27)
							)
						)
					)
				)
				(pin passive line
					(at 0 -13.97 0)
					(length 5.08)
					(hide yes)
					(name "VDDQ"
						(effects
							(font
								(size 1.27 1.27)
							)
						)
					)
					(number "E5"
						(effects
							(font
								(size 1.27 1.27)
							)
						)
					)
				)
				(pin passive line
					(at 0 -13.97 0)
					(length 5.08)
					(hide yes)
					(name "VDDQ"
						(effects
							(font
								(size 1.27 1.27)
							)
						)
					)
					(number "F1"
						(effects
							(font
								(size 1.27 1.27)
							)
						)
					)
				)
				(pin passive line
					(at 0 -13.97 0)
					(length 5.08)
					(hide yes)
					(name "VDDQ"
						(effects
							(font
								(size 1.27 1.27)
							)
						)
					)
					(number "F12"
						(effects
							(font
								(size 1.27 1.27)
							)
						)
					)
				)
				(pin passive line
					(at 0 -13.97 0)
					(length 5.08)
					(hide yes)
					(name "VDDQ"
						(effects
							(font
								(size 1.27 1.27)
							)
						)
					)
					(number "F13"
						(effects
							(font
								(size 1.27 1.27)
							)
						)
					)
				)
				(pin passive line
					(at 0 -13.97 0)
					(length 5.08)
					(hide yes)
					(name "VDDQ"
						(effects
							(font
								(size 1.27 1.27)
							)
						)
					)
					(number "F15"
						(effects
							(font
								(size 1.27 1.27)
							)
						)
					)
				)
				(pin passive line
					(at 0 -13.97 0)
					(length 5.08)
					(hide yes)
					(name "VDDQ"
						(effects
							(font
								(size 1.27 1.27)
							)
						)
					)
					(number "F3"
						(effects
							(font
								(size 1.27 1.27)
							)
						)
					)
				)
				(pin passive line
					(at 0 -13.97 0)
					(length 5.08)
					(hide yes)
					(name "VDDQ"
						(effects
							(font
								(size 1.27 1.27)
							)
						)
					)
					(number "F4"
						(effects
							(font
								(size 1.27 1.27)
							)
						)
					)
				)
				(pin passive line
					(at 0 -13.97 0)
					(length 5.08)
					(hide yes)
					(name "VDDQ"
						(effects
							(font
								(size 1.27 1.27)
							)
						)
					)
					(number "G1"
						(effects
							(font
								(size 1.27 1.27)
							)
						)
					)
				)
				(pin passive line
					(at 0 -13.97 0)
					(length 5.08)
					(hide yes)
					(name "VDDQ"
						(effects
							(font
								(size 1.27 1.27)
							)
						)
					)
					(number "G14"
						(effects
							(font
								(size 1.27 1.27)
							)
						)
					)
				)
				(pin passive line
					(at 0 -13.97 0)
					(length 5.08)
					(hide yes)
					(name "VDDQ"
						(effects
							(font
								(size 1.27 1.27)
							)
						)
					)
					(number "G15"
						(effects
							(font
								(size 1.27 1.27)
							)
						)
					)
				)
				(pin passive line
					(at 0 -13.97 0)
					(length 5.08)
					(hide yes)
					(name "VDDQ"
						(effects
							(font
								(size 1.27 1.27)
							)
						)
					)
					(number "G2"
						(effects
							(font
								(size 1.27 1.27)
							)
						)
					)
				)
				(pin passive line
					(at 0 -13.97 0)
					(length 5.08)
					(hide yes)
					(name "VDDQ"
						(effects
							(font
								(size 1.27 1.27)
							)
						)
					)
					(number "R1"
						(effects
							(font
								(size 1.27 1.27)
							)
						)
					)
				)
				(pin passive line
					(at 0 -13.97 0)
					(length 5.08)
					(hide yes)
					(name "VDDQ"
						(effects
							(font
								(size 1.27 1.27)
							)
						)
					)
					(number "R14"
						(effects
							(font
								(size 1.27 1.27)
							)
						)
					)
				)
				(pin passive line
					(at 0 -13.97 0)
					(length 5.08)
					(hide yes)
					(name "VDDQ"
						(effects
							(font
								(size 1.27 1.27)
							)
						)
					)
					(number "R15"
						(effects
							(font
								(size 1.27 1.27)
							)
						)
					)
				)
				(pin passive line
					(at 0 -13.97 0)
					(length 5.08)
					(hide yes)
					(name "VDDQ"
						(effects
							(font
								(size 1.27 1.27)
							)
						)
					)
					(number "R2"
						(effects
							(font
								(size 1.27 1.27)
							)
						)
					)
				)
				(pin passive line
					(at 0 -13.97 0)
					(length 5.08)
					(hide yes)
					(name "VDDQ"
						(effects
							(font
								(size 1.27 1.27)
							)
						)
					)
					(number "T1"
						(effects
							(font
								(size 1.27 1.27)
							)
						)
					)
				)
				(pin passive line
					(at 0 -13.97 0)
					(length 5.08)
					(hide yes)
					(name "VDDQ"
						(effects
							(font
								(size 1.27 1.27)
							)
						)
					)
					(number "T12"
						(effects
							(font
								(size 1.27 1.27)
							)
						)
					)
				)
				(pin passive line
					(at 0 -13.97 0)
					(length 5.08)
					(hide yes)
					(name "VDDQ"
						(effects
							(font
								(size 1.27 1.27)
							)
						)
					)
					(number "T13"
						(effects
							(font
								(size 1.27 1.27)
							)
						)
					)
				)
				(pin passive line
					(at 0 -13.97 0)
					(length 5.08)
					(hide yes)
					(name "VDDQ"
						(effects
							(font
								(size 1.27 1.27)
							)
						)
					)
					(number "T15"
						(effects
							(font
								(size 1.27 1.27)
							)
						)
					)
				)
				(pin passive line
					(at 0 -13.97 0)
					(length 5.08)
					(hide yes)
					(name "VDDQ"
						(effects
							(font
								(size 1.27 1.27)
							)
						)
					)
					(number "T3"
						(effects
							(font
								(size 1.27 1.27)
							)
						)
					)
				)
				(pin passive line
					(at 0 -13.97 0)
					(length 5.08)
					(hide yes)
					(name "VDDQ"
						(effects
							(font
								(size 1.27 1.27)
							)
						)
					)
					(number "T4"
						(effects
							(font
								(size 1.27 1.27)
							)
						)
					)
				)
				(pin passive line
					(at 0 -13.97 0)
					(length 5.08)
					(hide yes)
					(name "VDDQ"
						(effects
							(font
								(size 1.27 1.27)
							)
						)
					)
					(number "U11"
						(effects
							(font
								(size 1.27 1.27)
							)
						)
					)
				)
				(pin passive line
					(at 0 -13.97 0)
					(length 5.08)
					(hide yes)
					(name "VDDQ"
						(effects
							(font
								(size 1.27 1.27)
							)
						)
					)
					(number "U5"
						(effects
							(font
								(size 1.27 1.27)
							)
						)
					)
				)
				(pin passive line
					(at 0 -13.97 0)
					(length 5.08)
					(hide yes)
					(name "VDDQ"
						(effects
							(font
								(size 1.27 1.27)
							)
						)
					)
					(number "V12"
						(effects
							(font
								(size 1.27 1.27)
							)
						)
					)
				)
				(pin passive line
					(at 0 -13.97 0)
					(length 5.08)
					(hide yes)
					(name "VDDQ"
						(effects
							(font
								(size 1.27 1.27)
							)
						)
					)
					(number "V4"
						(effects
							(font
								(size 1.27 1.27)
							)
						)
					)
				)
				(pin passive line
					(at 0 -13.97 0)
					(length 5.08)
					(hide yes)
					(name "VDDQ"
						(effects
							(font
								(size 1.27 1.27)
							)
						)
					)
					(number "W13"
						(effects
							(font
								(size 1.27 1.27)
							)
						)
					)
				)
				(pin passive line
					(at 0 -13.97 0)
					(length 5.08)
					(hide yes)
					(name "VDDQ"
						(effects
							(font
								(size 1.27 1.27)
							)
						)
					)
					(number "W3"
						(effects
							(font
								(size 1.27 1.27)
							)
						)
					)
				)
				(pin passive line
					(at 0 -13.97 0)
					(length 5.08)
					(hide yes)
					(name "VDDQ"
						(effects
							(font
								(size 1.27 1.27)
							)
						)
					)
					(number "Y14"
						(effects
							(font
								(size 1.27 1.27)
							)
						)
					)
				)
				(pin passive line
					(at 0 -13.97 0)
					(length 5.08)
					(hide yes)
					(name "VDDQ"
						(effects
							(font
								(size 1.27 1.27)
							)
						)
					)
					(number "Y2"
						(effects
							(font
								(size 1.27 1.27)
							)
						)
					)
				)
				(pin passive line
					(at 0 -21.59 0)
					(length 5.08)
					(name "ZQ_A"
						(effects
							(font
								(size 1.27 1.27)
							)
						)
					)
					(number "H15"
						(effects
							(font
								(size 1.27 1.27)
							)
						)
					)
				)
				(pin passive line
					(at 0 -29.21 0)
					(length 5.08)
					(hide yes)
					(name "VSS"
						(effects
							(font
								(size 1.27 1.27)
							)
						)
					)
					(number "A11"
						(effects
							(font
								(size 1.27 1.27)
							)
						)
					)
				)
				(pin passive line
					(at 0 -29.21 0)
					(length 5.08)
					(name "VSS"
						(effects
							(font
								(size 1.27 1.27)
							)
						)
					)
					(number "A5"
						(effects
							(font
								(size 1.27 1.27)
							)
						)
					)
				)
				(pin passive line
					(at 0 -29.21 0)
					(length 5.08)
					(hide yes)
					(name "VSS"
						(effects
							(font
								(size 1.27 1.27)
							)
						)
					)
					(number "AA11"
						(effects
							(font
								(size 1.27 1.27)
							)
						)
					)
				)
				(pin passive line
					(at 0 -29.21 0)
					(length 5.08)
					(hide yes)
					(name "VSS"
						(effects
							(font
								(size 1.27 1.27)
							)
						)
					)
					(number "AA5"
						(effects
							(font
								(size 1.27 1.27)
							)
						)
					)
				)
				(pin passive line
					(at 0 -29.21 0)
					(length 5.08)
					(hide yes)
					(name "VSS"
						(effects
							(font
								(size 1.27 1.27)
							)
						)
					)
					(number "B12"
						(effects
							(font
								(size 1.27 1.27)
							)
						)
					)
				)
				(pin passive line
					(at 0 -29.21 0)
					(length 5.08)
					(hide yes)
					(name "VSS"
						(effects
							(font
								(size 1.27 1.27)
							)
						)
					)
					(number "B4"
						(effects
							(font
								(size 1.27 1.27)
							)
						)
					)
				)
				(pin passive line
					(at 0 -29.21 0)
					(length 5.08)
					(hide yes)
					(name "VSS"
						(effects
							(font
								(size 1.27 1.27)
							)
						)
					)
					(number "B8"
						(effects
							(font
								(size 1.27 1.27)
							)
						)
					)
				)
				(pin passive line
					(at 0 -29.21 0)
					(length 5.08)
					(hide yes)
					(name "VSS"
						(effects
							(font
								(size 1.27 1.27)
							)
						)
					)
					(number "C11"
						(effects
							(font
								(size 1.27 1.27)
							)
						)
					)
				)
				(pin passive line
					(at 0 -29.21 0)
					(length 5.08)
					(hide yes)
					(name "VSS"
						(effects
							(font
								(size 1.27 1.27)
							)
						)
					)
					(number "C5"
						(effects
							(font
								(size 1.27 1.27)
							)
						)
					)
				)
				(pin passive line
					(at 0 -29.21 0)
					(length 5.08)
					(hide yes)
					(name "VSS"
						(effects
							(font
								(size 1.27 1.27)
							)
						)
					)
					(number "C8"
						(effects
							(font
								(size 1.27 1.27)
							)
						)
					)
				)
				(pin passive line
					(at 0 -29.21 0)
					(length 5.08)
					(hide yes)
					(name "VSS"
						(effects
							(font
								(size 1.27 1.27)
							)
						)
					)
					(number "D10"
						(effects
							(font
								(size 1.27 1.27)
							)
						)
					)
				)
				(pin passive line
					(at 0 -29.21 0)
					(length 5.08)
					(hide yes)
					(name "VSS"
						(effects
							(font
								(size 1.27 1.27)
							)
						)
					)
					(number "D14"
						(effects
							(font
								(size 1.27 1.27)
							)
						)
					)
				)
				(pin passive line
					(at 0 -29.21 0)
					(length 5.08)
					(hide yes)
					(name "VSS"
						(effects
							(font
								(size 1.27 1.27)
							)
						)
					)
					(number "D2"
						(effects
							(font
								(size 1.27 1.27)
							)
						)
					)
				)
				(pin passive line
					(at 0 -29.21 0)
					(length 5.08)
					(hide yes)
					(name "VSS"
						(effects
							(font
								(size 1.27 1.27)
							)
						)
					)
					(number "D6"
						(effects
							(font
								(size 1.27 1.27)
							)
						)
					)
				)
				(pin passive line
					(at 0 -29.21 0)
					(length 5.08)
					(hide yes)
					(name "VSS"
						(effects
							(font
								(size 1.27 1.27)
							)
						)
					)
					(number "D7"
						(effects
							(font
								(size 1.27 1.27)
							)
						)
					)
				)
				(pin passive line
					(at 0 -29.21 0)
					(length 5.08)
					(hide yes)
					(name "VSS"
						(effects
							(font
								(size 1.27 1.27)
							)
						)
					)
					(number "D9"
						(effects
							(font
								(size 1.27 1.27)
							)
						)
					)
				)
				(pin passive line
					(at 0 -29.21 0)
					(length 5.08)
					(hide yes)
					(name "VSS"
						(effects
							(font
								(size 1.27 1.27)
							)
						)
					)
					(number "E1"
						(effects
							(font
								(size 1.27 1.27)
							)
						)
					)
				)
				(pin passive line
					(at 0 -29.21 0)
					(length 5.08)
					(hide yes)
					(name "VSS"
						(effects
							(font
								(size 1.27 1.27)
							)
						)
					)
					(number "E13"
						(effects
							(font
								(size 1.27 1.27)
							)
						)
					)
				)
				(pin passive line
					(at 0 -29.21 0)
					(length 5.08)
					(hide yes)
					(name "VSS"
						(effects
							(font
								(size 1.27 1.27)
							)
						)
					)
					(number "E15"
						(effects
							(font
								(size 1.27 1.27)
							)
						)
					)
				)
				(pin passive line
					(at 0 -29.21 0)
					(length 5.08)
					(hide yes)
					(name "VSS"
						(effects
							(font
								(size 1.27 1.27)
							)
						)
					)
					(number "E3"
						(effects
							(font
								(size 1.27 1.27)
							)
						)
					)
				)
				(pin passive line
					(at 0 -29.21 0)
					(length 5.08)
					(hide yes)
					(name "VSS"
						(effects
							(font
								(size 1.27 1.27)
							)
						)
					)
					(number "E8"
						(effects
							(font
								(size 1.27 1.27)
							)
						)
					)
				)
				(pin passive line
					(at 0 -29.21 0)
					(length 5.08)
					(hide yes)
					(name "VSS"
						(effects
							(font
								(size 1.27 1.27)
							)
						)
					)
					(number "F14"
						(effects
							(font
								(size 1.27 1.27)
							)
						)
					)
				)
				(pin passive line
					(at 0 -29.21 0)
					(length 5.08)
					(hide yes)
					(name "VSS"
						(effects
							(font
								(size 1.27 1.27)
							)
						)
					)
					(number "F2"
						(effects
							(font
								(size 1.27 1.27)
							)
						)
					)
				)
				(pin passive line
					(at 0 -29.21 0)
					(length 5.08)
					(hide yes)
					(name "VSS"
						(effects
							(font
								(size 1.27 1.27)
							)
						)
					)
					(number "F8"
						(effects
							(font
								(size 1.27 1.27)
							)
						)
					)
				)
				(pin passive line
					(at 0 -29.21 0)
					(length 5.08)
					(hide yes)
					(name "VSS"
						(effects
							(font
								(size 1.27 1.27)
							)
						)
					)
					(number "G11"
						(effects
							(font
								(size 1.27 1.27)
							)
						)
					)
				)
				(pin passive line
					(at 0 -29.21 0)
					(length 5.08)
					(hide yes)
					(name "VSS"
						(effects
							(font
								(size 1.27 1.27)
							)
						)
					)
					(number "G13"
						(effects
							(font
								(size 1.27 1.27)
							)
						)
					)
				)
				(pin passive line
					(at 0 -29.21 0)
					(length 5.08)
					(hide yes)
					(name "VSS"
						(effects
							(font
								(size 1.27 1.27)
							)
						)
					)
					(number "G3"
						(effects
							(font
								(size 1.27 1.27)
							)
						)
					)
				)
				(pin passive line
					(at 0 -29.21 0)
					(length 5.08)
					(hide yes)
					(name "VSS"
						(effects
							(font
								(size 1.27 1.27)
							)
						)
					)
					(number "G5"
						(effects
							(font
								(size 1.27 1.27)
							)
						)
					)
				)
				(pin passive line
					(at 0 -29.21 0)
					(length 5.08)
					(hide yes)
					(name "VSS"
						(effects
							(font
								(size 1.27 1.27)
							)
						)
					)
					(number "G7"
						(effects
							(font
								(size 1.27 1.27)
							)
						)
					)
				)
				(pin passive line
					(at 0 -29.21 0)
					(length 5.08)
					(hide yes)
					(name "VSS"
						(effects
							(font
								(size 1.27 1.27)
							)
						)
					)
					(number "G9"
						(effects
							(font
								(size 1.27 1.27)
							)
						)
					)
				)
				(pin passive line
					(at 0 -29.21 0)
					(length 5.08)
					(hide yes)
					(name "VSS"
						(effects
							(font
								(size 1.27 1.27)
							)
						)
					)
					(number "H10"
						(effects
							(font
								(size 1.27 1.27)
							)
						)
					)
				)
				(pin passive line
					(at 0 -29.21 0)
					(length 5.08)
					(hide yes)
					(name "VSS"
						(effects
							(font
								(size 1.27 1.27)
							)
						)
					)
					(number "H12"
						(effects
							(font
								(size 1.27 1.27)
							)
						)
					)
				)
				(pin passive line
					(at 0 -29.21 0)
					(length 5.08)
					(hide yes)
					(name "VSS"
						(effects
							(font
								(size 1.27 1.27)
							)
						)
					)
					(number "H3"
						(effects
							(font
								(size 1.27 1.27)
							)
						)
					)
				)
				(pin passive line
					(at 0 -29.21 0)
					(length 5.08)
					(hide yes)
					(name "VSS"
						(effects
							(font
								(size 1.27 1.27)
							)
						)
					)
					(number "H4"
						(effects
							(font
								(size 1.27 1.27)
							)
						)
					)
				)
				(pin passive line
					(at 0 -29.21 0)
					(length 5.08)
					(hide yes)
					(name "VSS"
						(effects
							(font
								(size 1.27 1.27)
							)
						)
					)
					(number "H6"
						(effects
							(font
								(size 1.27 1.27)
							)
						)
					)
				)
				(pin passive line
					(at 0 -29.21 0)
					(length 5.08)
					(hide yes)
					(name "VSS"
						(effects
							(font
								(size 1.27 1.27)
							)
						)
					)
					(number "H8"
						(effects
							(font
								(size 1.27 1.27)
							)
						)
					)
				)
				(pin passive line
					(at 0 -29.21 0)
					(length 5.08)
					(hide yes)
					(name "VSS"
						(effects
							(font
								(size 1.27 1.27)
							)
						)
					)
					(number "J1"
						(effects
							(font
								(size 1.27 1.27)
							)
						)
					)
				)
				(pin passive line
					(at 0 -29.21 0)
					(length 5.08)
					(hide yes)
					(name "VSS"
						(effects
							(font
								(size 1.27 1.27)
							)
						)
					)
					(number "J10"
						(effects
							(font
								(size 1.27 1.27)
							)
						)
					)
				)
				(pin passive line
					(at 0 -29.21 0)
					(length 5.08)
					(hide yes)
					(name "VSS"
						(effects
							(font
								(size 1.27 1.27)
							)
						)
					)
					(number "J12"
						(effects
							(font
								(size 1.27 1.27)
							)
						)
					)
				)
				(pin passive line
					(at 0 -29.21 0)
					(length 5.08)
					(hide yes)
					(name "VSS"
						(effects
							(font
								(size 1.27 1.27)
							)
						)
					)
					(number "J13"
						(effects
							(font
								(size 1.27 1.27)
							)
						)
					)
				)
				(pin passive line
					(at 0 -29.21 0)
					(length 5.08)
					(hide yes)
					(name "VSS"
						(effects
							(font
								(size 1.27 1.27)
							)
						)
					)
					(number "J15"
						(effects
							(font
								(size 1.27 1.27)
							)
						)
					)
				)
				(pin passive line
					(at 0 -29.21 0)
					(length 5.08)
					(hide yes)
					(name "VSS"
						(effects
							(font
								(size 1.27 1.27)
							)
						)
					)
					(number "J3"
						(effects
							(font
								(size 1.27 1.27)
							)
						)
					)
				)
				(pin passive line
					(at 0 -29.21 0)
					(length 5.08)
					(hide yes)
					(name "VSS"
						(effects
							(font
								(size 1.27 1.27)
							)
						)
					)
					(number "J7"
						(effects
							(font
								(size 1.27 1.27)
							)
						)
					)
				)
				(pin passive line
					(at 0 -29.21 0)
					(length 5.08)
					(hide yes)
					(name "VSS"
						(effects
							(font
								(size 1.27 1.27)
							)
						)
					)
					(number "J8"
						(effects
							(font
								(size 1.27 1.27)
							)
						)
					)
				)
				(pin passive line
					(at 0 -29.21 0)
					(length 5.08)
					(hide yes)
					(name "VSS"
						(effects
							(font
								(size 1.27 1.27)
							)
						)
					)
					(number "K7"
						(effects
							(font
								(size 1.27 1.27)
							)
						)
					)
				)
				(pin passive line
					(at 0 -29.21 0)
					(length 5.08)
					(hide yes)
					(name "VSS"
						(effects
							(font
								(size 1.27 1.27)
							)
						)
					)
					(number "K8"
						(effects
							(font
								(size 1.27 1.27)
							)
						)
					)
				)
				(pin passive line
					(at 0 -29.21 0)
					(length 5.08)
					(hide yes)
					(name "VSS"
						(effects
							(font
								(size 1.27 1.27)
							)
						)
					)
					(number "K9"
						(effects
							(font
								(size 1.27 1.27)
							)
						)
					)
				)
				(pin passive line
					(at 0 -29.21 0)
					(length 5.08)
					(hide yes)
					(name "VSS"
						(effects
							(font
								(size 1.27 1.27)
							)
						)
					)
					(number "L1"
						(effects
							(font
								(size 1.27 1.27)
							)
						)
					)
				)
				(pin passive line
					(at 0 -29.21 0)
					(length 5.08)
					(hide yes)
					(name "VSS"
						(effects
							(font
								(size 1.27 1.27)
							)
						)
					)
					(number "L11"
						(effects
							(font
								(size 1.27 1.27)
							)
						)
					)
				)
				(pin passive line
					(at 0 -29.21 0)
					(length 5.08)
					(hide yes)
					(name "VSS"
						(effects
							(font
								(size 1.27 1.27)
							)
						)
					)
					(number "L12"
						(effects
							(font
								(size 1.27 1.27)
							)
						)
					)
				)
				(pin passive line
					(at 0 -29.21 0)
					(length 5.08)
					(hide yes)
					(name "VSS"
						(effects
							(font
								(size 1.27 1.27)
							)
						)
					)
					(number "L13"
						(effects
							(font
								(size 1.27 1.27)
							)
						)
					)
				)
				(pin passive line
					(at 0 -29.21 0)
					(length 5.08)
					(hide yes)
					(name "VSS"
						(effects
							(font
								(size 1.27 1.27)
							)
						)
					)
					(number "L14"
						(effects
							(font
								(size 1.27 1.27)
							)
						)
					)
				)
				(pin passive line
					(at 0 -29.21 0)
					(length 5.08)
					(hide yes)
					(name "VSS"
						(effects
							(font
								(size 1.27 1.27)
							)
						)
					)
					(number "L15"
						(effects
							(font
								(size 1.27 1.27)
							)
						)
					)
				)
				(pin passive line
					(at 0 -29.21 0)
					(length 5.08)
					(hide yes)
					(name "VSS"
						(effects
							(font
								(size 1.27 1.27)
							)
						)
					)
					(number "L2"
						(effects
							(font
								(size 1.27 1.27)
							)
						)
					)
				)
				(pin passive line
					(at 0 -29.21 0)
					(length 5.08)
					(hide yes)
					(name "VSS"
						(effects
							(font
								(size 1.27 1.27)
							)
						)
					)
					(number "L3"
						(effects
							(font
								(size 1.27 1.27)
							)
						)
					)
				)
				(pin passive line
					(at 0 -29.21 0)
					(length 5.08)
					(hide yes)
					(name "VSS"
						(effects
							(font
								(size 1.27 1.27)
							)
						)
					)
					(number "L4"
						(effects
							(font
								(size 1.27 1.27)
							)
						)
					)
				)
				(pin passive line
					(at 0 -29.21 0)
					(length 5.08)
					(hide yes)
					(name "VSS"
						(effects
							(font
								(size 1.27 1.27)
							)
						)
					)
					(number "L5"
						(effects
							(font
								(size 1.27 1.27)
							)
						)
					)
				)
				(pin passive line
					(at 0 -29.21 0)
					(length 5.08)
					(hide yes)
					(name "VSS"
						(effects
							(font
								(size 1.27 1.27)
							)
						)
					)
					(number "M7"
						(effects
							(font
								(size 1.27 1.27)
							)
						)
					)
				)
				(pin passive line
					(at 0 -29.21 0)
					(length 5.08)
					(hide yes)
					(name "VSS"
						(effects
							(font
								(size 1.27 1.27)
							)
						)
					)
					(number "M8"
						(effects
							(font
								(size 1.27 1.27)
							)
						)
					)
				)
				(pin passive line
					(at 0 -29.21 0)
					(length 5.08)
					(hide yes)
					(name "VSS"
						(effects
							(font
								(size 1.27 1.27)
							)
						)
					)
					(number "M9"
						(effects
							(font
								(size 1.27 1.27)
							)
						)
					)
				)
				(pin passive line
					(at 0 -29.21 0)
					(length 5.08)
					(hide yes)
					(name "VSS"
						(effects
							(font
								(size 1.27 1.27)
							)
						)
					)
					(number "N1"
						(effects
							(font
								(size 1.27 1.27)
							)
						)
					)
				)
				(pin passive line
					(at 0 -29.21 0)
					(length 5.08)
					(hide yes)
					(name "VSS"
						(effects
							(font
								(size 1.27 1.27)
							)
						)
					)
					(number "N10"
						(effects
							(font
								(size 1.27 1.27)
							)
						)
					)
				)
				(pin passive line
					(at 0 -29.21 0)
					(length 5.08)
					(hide yes)
					(name "VSS"
						(effects
							(font
								(size 1.27 1.27)
							)
						)
					)
					(number "N12"
						(effects
							(font
								(size 1.27 1.27)
							)
						)
					)
				)
				(pin passive line
					(at 0 -29.21 0)
					(length 5.08)
					(hide yes)
					(name "VSS"
						(effects
							(font
								(size 1.27 1.27)
							)
						)
					)
					(number "N13"
						(effects
							(font
								(size 1.27 1.27)
							)
						)
					)
				)
				(pin passive line
					(at 0 -29.21 0)
					(length 5.08)
					(hide yes)
					(name "VSS"
						(effects
							(font
								(size 1.27 1.27)
							)
						)
					)
					(number "N15"
						(effects
							(font
								(size 1.27 1.27)
							)
						)
					)
				)
				(pin passive line
					(at 0 -29.21 0)
					(length 5.08)
					(hide yes)
					(name "VSS"
						(effects
							(font
								(size 1.27 1.27)
							)
						)
					)
					(number "N3"
						(effects
							(font
								(size 1.27 1.27)
							)
						)
					)
				)
				(pin passive line
					(at 0 -29.21 0)
					(length 5.08)
					(hide yes)
					(name "VSS"
						(effects
							(font
								(size 1.27 1.27)
							)
						)
					)
					(number "N4"
						(effects
							(font
								(size 1.27 1.27)
							)
						)
					)
				)
				(pin passive line
					(at 0 -29.21 0)
					(length 5.08)
					(hide yes)
					(name "VSS"
						(effects
							(font
								(size 1.27 1.27)
							)
						)
					)
					(number "N6"
						(effects
							(font
								(size 1.27 1.27)
							)
						)
					)
				)
				(pin passive line
					(at 0 -29.21 0)
					(length 5.08)
					(hide yes)
					(name "VSS"
						(effects
							(font
								(size 1.27 1.27)
							)
						)
					)
					(number "N8"
						(effects
							(font
								(size 1.27 1.27)
							)
						)
					)
				)
				(pin passive line
					(at 0 -29.21 0)
					(length 5.08)
					(hide yes)
					(name "VSS"
						(effects
							(font
								(size 1.27 1.27)
							)
						)
					)
					(number "N9"
						(effects
							(font
								(size 1.27 1.27)
							)
						)
					)
				)
				(pin passive line
					(at 0 -29.21 0)
					(length 5.08)
					(hide yes)
					(name "VSS"
						(effects
							(font
								(size 1.27 1.27)
							)
						)
					)
					(number "P10"
						(effects
							(font
								(size 1.27 1.27)
							)
						)
					)
				)
				(pin passive line
					(at 0 -29.21 0)
					(length 5.08)
					(hide yes)
					(name "VSS"
						(effects
							(font
								(size 1.27 1.27)
							)
						)
					)
					(number "P12"
						(effects
							(font
								(size 1.27 1.27)
							)
						)
					)
				)
				(pin passive line
					(at 0 -29.21 0)
					(length 5.08)
					(hide yes)
					(name "VSS"
						(effects
							(font
								(size 1.27 1.27)
							)
						)
					)
					(number "P13"
						(effects
							(font
								(size 1.27 1.27)
							)
						)
					)
				)
				(pin passive line
					(at 0 -29.21 0)
					(length 5.08)
					(hide yes)
					(name "VSS"
						(effects
							(font
								(size 1.27 1.27)
							)
						)
					)
					(number "P4"
						(effects
							(font
								(size 1.27 1.27)
							)
						)
					)
				)
				(pin passive line
					(at 0 -29.21 0)
					(length 5.08)
					(hide yes)
					(name "VSS"
						(effects
							(font
								(size 1.27 1.27)
							)
						)
					)
					(number "P6"
						(effects
							(font
								(size 1.27 1.27)
							)
						)
					)
				)
				(pin passive line
					(at 0 -29.21 0)
					(length 5.08)
					(hide yes)
					(name "VSS"
						(effects
							(font
								(size 1.27 1.27)
							)
						)
					)
					(number "P8"
						(effects
							(font
								(size 1.27 1.27)
							)
						)
					)
				)
				(pin passive line
					(at 0 -29.21 0)
					(length 5.08)
					(hide yes)
					(name "VSS"
						(effects
							(font
								(size 1.27 1.27)
							)
						)
					)
					(number "R11"
						(effects
							(font
								(size 1.27 1.27)
							)
						)
					)
				)
				(pin passive line
					(at 0 -29.21 0)
					(length 5.08)
					(hide yes)
					(name "VSS"
						(effects
							(font
								(size 1.27 1.27)
							)
						)
					)
					(number "R13"
						(effects
							(font
								(size 1.27 1.27)
							)
						)
					)
				)
				(pin passive line
					(at 0 -29.21 0)
					(length 5.08)
					(hide yes)
					(name "VSS"
						(effects
							(font
								(size 1.27 1.27)
							)
						)
					)
					(number "R3"
						(effects
							(font
								(size 1.27 1.27)
							)
						)
					)
				)
				(pin passive line
					(at 0 -29.21 0)
					(length 5.08)
					(hide yes)
					(name "VSS"
						(effects
							(font
								(size 1.27 1.27)
							)
						)
					)
					(number "R5"
						(effects
							(font
								(size 1.27 1.27)
							)
						)
					)
				)
				(pin passive line
					(at 0 -29.21 0)
					(length 5.08)
					(hide yes)
					(name "VSS"
						(effects
							(font
								(size 1.27 1.27)
							)
						)
					)
					(number "R7"
						(effects
							(font
								(size 1.27 1.27)
							)
						)
					)
				)
				(pin passive line
					(at 0 -29.21 0)
					(length 5.08)
					(hide yes)
					(name "VSS"
						(effects
							(font
								(size 1.27 1.27)
							)
						)
					)
					(number "R9"
						(effects
							(font
								(size 1.27 1.27)
							)
						)
					)
				)
				(pin passive line
					(at 0 -29.21 0)
					(length 5.08)
					(hide yes)
					(name "VSS"
						(effects
							(font
								(size 1.27 1.27)
							)
						)
					)
					(number "T14"
						(effects
							(font
								(size 1.27 1.27)
							)
						)
					)
				)
				(pin passive line
					(at 0 -29.21 0)
					(length 5.08)
					(hide yes)
					(name "VSS"
						(effects
							(font
								(size 1.27 1.27)
							)
						)
					)
					(number "T2"
						(effects
							(font
								(size 1.27 1.27)
							)
						)
					)
				)
				(pin passive line
					(at 0 -29.21 0)
					(length 5.08)
					(hide yes)
					(name "VSS"
						(effects
							(font
								(size 1.27 1.27)
							)
						)
					)
					(number "T8"
						(effects
							(font
								(size 1.27 1.27)
							)
						)
					)
				)
				(pin passive line
					(at 0 -29.21 0)
					(length 5.08)
					(hide yes)
					(name "VSS"
						(effects
							(font
								(size 1.27 1.27)
							)
						)
					)
					(number "U1"
						(effects
							(font
								(size 1.27 1.27)
							)
						)
					)
				)
				(pin passive line
					(at 0 -29.21 0)
					(length 5.08)
					(hide yes)
					(name "VSS"
						(effects
							(font
								(size 1.27 1.27)
							)
						)
					)
					(number "U13"
						(effects
							(font
								(size 1.27 1.27)
							)
						)
					)
				)
				(pin passive line
					(at 0 -29.21 0)
					(length 5.08)
					(hide yes)
					(name "VSS"
						(effects
							(font
								(size 1.27 1.27)
							)
						)
					)
					(number "U15"
						(effects
							(font
								(size 1.27 1.27)
							)
						)
					)
				)
				(pin passive line
					(at 0 -29.21 0)
					(length 5.08)
					(hide yes)
					(name "VSS"
						(effects
							(font
								(size 1.27 1.27)
							)
						)
					)
					(number "U3"
						(effects
							(font
								(size 1.27 1.27)
							)
						)
					)
				)
				(pin passive line
					(at 0 -29.21 0)
					(length 5.08)
					(hide yes)
					(name "VSS"
						(effects
							(font
								(size 1.27 1.27)
							)
						)
					)
					(number "U8"
						(effects
							(font
								(size 1.27 1.27)
							)
						)
					)
				)
				(pin passive line
					(at 0 -29.21 0)
					(length 5.08)
					(hide yes)
					(name "VSS"
						(effects
							(font
								(size 1.27 1.27)
							)
						)
					)
					(number "V10"
						(effects
							(font
								(size 1.27 1.27)
							)
						)
					)
				)
				(pin passive line
					(at 0 -29.21 0)
					(length 5.08)
					(hide yes)
					(name "VSS"
						(effects
							(font
								(size 1.27 1.27)
							)
						)
					)
					(number "V14"
						(effects
							(font
								(size 1.27 1.27)
							)
						)
					)
				)
				(pin passive line
					(at 0 -29.21 0)
					(length 5.08)
					(hide yes)
					(name "VSS"
						(effects
							(font
								(size 1.27 1.27)
							)
						)
					)
					(number "V2"
						(effects
							(font
								(size 1.27 1.27)
							)
						)
					)
				)
				(pin passive line
					(at 0 -29.21 0)
					(length 5.08)
					(hide yes)
					(name "VSS"
						(effects
							(font
								(size 1.27 1.27)
							)
						)
					)
					(number "V6"
						(effects
							(font
								(size 1.27 1.27)
							)
						)
					)
				)
				(pin passive line
					(at 0 -29.21 0)
					(length 5.08)
					(hide yes)
					(name "VSS"
						(effects
							(font
								(size 1.27 1.27)
							)
						)
					)
					(number "V7"
						(effects
							(font
								(size 1.27 1.27)
							)
						)
					)
				)
				(pin passive line
					(at 0 -29.21 0)
					(length 5.08)
					(hide yes)
					(name "VSS"
						(effects
							(font
								(size 1.27 1.27)
							)
						)
					)
					(number "V9"
						(effects
							(font
								(size 1.27 1.27)
							)
						)
					)
				)
				(pin passive line
					(at 0 -29.21 0)
					(length 5.08)
					(hide yes)
					(name "VSS"
						(effects
							(font
								(size 1.27 1.27)
							)
						)
					)
					(number "W11"
						(effects
							(font
								(size 1.27 1.27)
							)
						)
					)
				)
				(pin passive line
					(at 0 -29.21 0)
					(length 5.08)
					(hide yes)
					(name "VSS"
						(effects
							(font
								(size 1.27 1.27)
							)
						)
					)
					(number "W5"
						(effects
							(font
								(size 1.27 1.27)
							)
						)
					)
				)
				(pin passive line
					(at 0 -29.21 0)
					(length 5.08)
					(hide yes)
					(name "VSS"
						(effects
							(font
								(size 1.27 1.27)
							)
						)
					)
					(number "W8"
						(effects
							(font
								(size 1.27 1.27)
							)
						)
					)
				)
				(pin passive line
					(at 0 -29.21 0)
					(length 5.08)
					(hide yes)
					(name "VSS"
						(effects
							(font
								(size 1.27 1.27)
							)
						)
					)
					(number "Y12"
						(effects
							(font
								(size 1.27 1.27)
							)
						)
					)
				)
				(pin passive line
					(at 0 -29.21 0)
					(length 5.08)
					(hide yes)
					(name "VSS"
						(effects
							(font
								(size 1.27 1.27)
							)
						)
					)
					(number "Y4"
						(effects
							(font
								(size 1.27 1.27)
							)
						)
					)
				)
				(pin passive line
					(at 0 -29.21 0)
					(length 5.08)
					(hide yes)
					(name "VSS"
						(effects
							(font
								(size 1.27 1.27)
							)
						)
					)
					(number "Y8"
						(effects
							(font
								(size 1.27 1.27)
							)
						)
					)
				)
				(pin no_connect line
					(at 29.21 1.27 180)
					(length 5.08)
					(hide yes)
					(name "RFU"
						(effects
							(font
								(size 1.27 1.27)
							)
						)
					)
					(number "P1"
						(effects
							(font
								(size 1.27 1.27)
							)
						)
					)
				)
				(pin no_connect line
					(at 29.21 0 180)
					(length 5.08)
					(hide yes)
					(name "RFU"
						(effects
							(font
								(size 1.27 1.27)
							)
						)
					)
					(number "J6"
						(effects
							(font
								(size 1.27 1.27)
							)
						)
					)
				)
				(pin no_connect line
					(at 29.21 -1.27 180)
					(length 5.08)
					(hide yes)
					(name "RFU"
						(effects
							(font
								(size 1.27 1.27)
							)
						)
					)
					(number "J4"
						(effects
							(font
								(size 1.27 1.27)
							)
						)
					)
				)
				(pin no_connect line
					(at 29.21 -2.54 180)
					(length 5.08)
					(hide yes)
					(name "RFU"
						(effects
							(font
								(size 1.27 1.27)
							)
						)
					)
					(number "P15"
						(effects
							(font
								(size 1.27 1.27)
							)
						)
					)
				)
				(pin no_connect line
					(at 29.21 -3.81 180)
					(length 5.08)
					(hide yes)
					(name "NC"
						(effects
							(font
								(size 1.27 1.27)
							)
						)
					)
					(number "A1"
						(effects
							(font
								(size 1.27 1.27)
							)
						)
					)
				)
				(pin no_connect line
					(at 29.21 -17.78 180)
					(length 5.08)
					(hide yes)
					(name "NC"
						(effects
							(font
								(size 1.27 1.27)
							)
						)
					)
					(number "A2"
						(effects
							(font
								(size 1.27 1.27)
							)
						)
					)
				)
				(pin no_connect line
					(at 29.21 -19.05 180)
					(length 5.08)
					(hide yes)
					(name "NC"
						(effects
							(font
								(size 1.27 1.27)
							)
						)
					)
					(number "A14"
						(effects
							(font
								(size 1.27 1.27)
							)
						)
					)
				)
				(pin no_connect line
					(at 29.21 -20.32 180)
					(length 5.08)
					(hide yes)
					(name "NC"
						(effects
							(font
								(size 1.27 1.27)
							)
						)
					)
					(number "A15"
						(effects
							(font
								(size 1.27 1.27)
							)
						)
					)
				)
				(pin no_connect line
					(at 29.21 -21.59 180)
					(length 5.08)
					(hide yes)
					(name "NC"
						(effects
							(font
								(size 1.27 1.27)
							)
						)
					)
					(number "B1"
						(effects
							(font
								(size 1.27 1.27)
							)
						)
					)
				)
				(pin no_connect line
					(at 29.21 -22.86 180)
					(length 5.08)
					(hide yes)
					(name "NC"
						(effects
							(font
								(size 1.27 1.27)
							)
						)
					)
					(number "B15"
						(effects
							(font
								(size 1.27 1.27)
							)
						)
					)
				)
				(pin no_connect line
					(at 29.21 -24.13 180)
					(length 5.08)
					(hide yes)
					(name "NC"
						(effects
							(font
								(size 1.27 1.27)
							)
						)
					)
					(number "Y1"
						(effects
							(font
								(size 1.27 1.27)
							)
						)
					)
				)
				(pin no_connect line
					(at 29.21 -25.4 180)
					(length 5.08)
					(hide yes)
					(name "NC"
						(effects
							(font
								(size 1.27 1.27)
							)
						)
					)
					(number "Y15"
						(effects
							(font
								(size 1.27 1.27)
							)
						)
					)
				)
				(pin no_connect line
					(at 29.21 -26.67 180)
					(length 5.08)
					(hide yes)
					(name "NC"
						(effects
							(font
								(size 1.27 1.27)
							)
						)
					)
					(number "AA1"
						(effects
							(font
								(size 1.27 1.27)
							)
						)
					)
				)
				(pin no_connect line
					(at 29.21 -27.94 180)
					(length 5.08)
					(hide yes)
					(name "NC"
						(effects
							(font
								(size 1.27 1.27)
							)
						)
					)
					(number "AA2"
						(effects
							(font
								(size 1.27 1.27)
							)
						)
					)
				)
				(pin no_connect line
					(at 29.21 -29.21 180)
					(length 5.08)
					(hide yes)
					(name "NC"
						(effects
							(font
								(size 1.27 1.27)
							)
						)
					)
					(number "AA14"
						(effects
							(font
								(size 1.27 1.27)
							)
						)
					)
				)
				(pin no_connect line
					(at 29.21 -30.48 180)
					(length 5.08)
					(hide yes)
					(name "NC"
						(effects
							(font
								(size 1.27 1.27)
							)
						)
					)
					(number "AA15"
						(effects
							(font
								(size 1.27 1.27)
							)
						)
					)
				)
				(pin passive line
					(at 34.29 -6.35 180)
					(length 5.08)
					(name "VDD2H"
						(effects
							(font
								(size 1.27 1.27)
							)
						)
					)
					(number "A7"
						(effects
							(font
								(size 1.27 1.27)
							)
						)
					)
				)
				(pin passive line
					(at 34.29 -6.35 180)
					(length 5.08)
					(hide yes)
					(name "VDD2H"
						(effects
							(font
								(size 1.27 1.27)
							)
						)
					)
					(number "A8"
						(effects
							(font
								(size 1.27 1.27)
							)
						)
					)
				)
				(pin passive line
					(at 34.29 -6.35 180)
					(length 5.08)
					(hide yes)
					(name "VDD2H"
						(effects
							(font
								(size 1.27 1.27)
							)
						)
					)
					(number "A9"
						(effects
							(font
								(size 1.27 1.27)
							)
						)
					)
				)
				(pin passive line
					(at 34.29 -6.35 180)
					(length 5.08)
					(hide yes)
					(name "VDD2H"
						(effects
							(font
								(size 1.27 1.27)
							)
						)
					)
					(number "AA7"
						(effects
							(font
								(size 1.27 1.27)
							)
						)
					)
				)
				(pin passive line
					(at 34.29 -6.35 180)
					(length 5.08)
					(hide yes)
					(name "VDD2H"
						(effects
							(font
								(size 1.27 1.27)
							)
						)
					)
					(number "AA8"
						(effects
							(font
								(size 1.27 1.27)
							)
						)
					)
				)
				(pin passive line
					(at 34.29 -6.35 180)
					(length 5.08)
					(hide yes)
					(name "VDD2H"
						(effects
							(font
								(size 1.27 1.27)
							)
						)
					)
					(number "AA9"
						(effects
							(font
								(size 1.27 1.27)
							)
						)
					)
				)
				(pin passive line
					(at 34.29 -6.35 180)
					(length 5.08)
					(hide yes)
					(name "VDD2H"
						(effects
							(font
								(size 1.27 1.27)
							)
						)
					)
					(number "B7"
						(effects
							(font
								(size 1.27 1.27)
							)
						)
					)
				)
				(pin passive line
					(at 34.29 -6.35 180)
					(length 5.08)
					(hide yes)
					(name "VDD2H"
						(effects
							(font
								(size 1.27 1.27)
							)
						)
					)
					(number "B9"
						(effects
							(font
								(size 1.27 1.27)
							)
						)
					)
				)
				(pin passive line
					(at 34.29 -6.35 180)
					(length 5.08)
					(hide yes)
					(name "VDD2H"
						(effects
							(font
								(size 1.27 1.27)
							)
						)
					)
					(number "C7"
						(effects
							(font
								(size 1.27 1.27)
							)
						)
					)
				)
				(pin passive line
					(at 34.29 -6.35 180)
					(length 5.08)
					(hide yes)
					(name "VDD2H"
						(effects
							(font
								(size 1.27 1.27)
							)
						)
					)
					(number "C9"
						(effects
							(font
								(size 1.27 1.27)
							)
						)
					)
				)
				(pin passive line
					(at 34.29 -6.35 180)
					(length 5.08)
					(hide yes)
					(name "VDD2H"
						(effects
							(font
								(size 1.27 1.27)
							)
						)
					)
					(number "D8"
						(effects
							(font
								(size 1.27 1.27)
							)
						)
					)
				)
				(pin passive line
					(at 34.29 -6.35 180)
					(length 5.08)
					(hide yes)
					(name "VDD2H"
						(effects
							(font
								(size 1.27 1.27)
							)
						)
					)
					(number "E7"
						(effects
							(font
								(size 1.27 1.27)
							)
						)
					)
				)
				(pin passive line
					(at 34.29 -6.35 180)
					(length 5.08)
					(hide yes)
					(name "VDD2H"
						(effects
							(font
								(size 1.27 1.27)
							)
						)
					)
					(number "E9"
						(effects
							(font
								(size 1.27 1.27)
							)
						)
					)
				)
				(pin passive line
					(at 34.29 -6.35 180)
					(length 5.08)
					(hide yes)
					(name "VDD2H"
						(effects
							(font
								(size 1.27 1.27)
							)
						)
					)
					(number "F10"
						(effects
							(font
								(size 1.27 1.27)
							)
						)
					)
				)
				(pin passive line
					(at 34.29 -6.35 180)
					(length 5.08)
					(hide yes)
					(name "VDD2H"
						(effects
							(font
								(size 1.27 1.27)
							)
						)
					)
					(number "F6"
						(effects
							(font
								(size 1.27 1.27)
							)
						)
					)
				)
				(pin passive line
					(at 34.29 -6.35 180)
					(length 5.08)
					(hide yes)
					(name "VDD2H"
						(effects
							(font
								(size 1.27 1.27)
							)
						)
					)
					(number "F7"
						(effects
							(font
								(size 1.27 1.27)
							)
						)
					)
				)
				(pin passive line
					(at 34.29 -6.35 180)
					(length 5.08)
					(hide yes)
					(name "VDD2H"
						(effects
							(font
								(size 1.27 1.27)
							)
						)
					)
					(number "F9"
						(effects
							(font
								(size 1.27 1.27)
							)
						)
					)
				)
				(pin passive line
					(at 34.29 -6.35 180)
					(length 5.08)
					(hide yes)
					(name "VDD2H"
						(effects
							(font
								(size 1.27 1.27)
							)
						)
					)
					(number "J11"
						(effects
							(font
								(size 1.27 1.27)
							)
						)
					)
				)
				(pin passive line
					(at 34.29 -6.35 180)
					(length 5.08)
					(hide yes)
					(name "VDD2H"
						(effects
							(font
								(size 1.27 1.27)
							)
						)
					)
					(number "J5"
						(effects
							(font
								(size 1.27 1.27)
							)
						)
					)
				)
				(pin passive line
					(at 34.29 -6.35 180)
					(length 5.08)
					(hide yes)
					(name "VDD2H"
						(effects
							(font
								(size 1.27 1.27)
							)
						)
					)
					(number "K1"
						(effects
							(font
								(size 1.27 1.27)
							)
						)
					)
				)
				(pin passive line
					(at 34.29 -6.35 180)
					(length 5.08)
					(hide yes)
					(name "VDD2H"
						(effects
							(font
								(size 1.27 1.27)
							)
						)
					)
					(number "K10"
						(effects
							(font
								(size 1.27 1.27)
							)
						)
					)
				)
				(pin passive line
					(at 34.29 -6.35 180)
					(length 5.08)
					(hide yes)
					(name "VDD2H"
						(effects
							(font
								(size 1.27 1.27)
							)
						)
					)
					(number "K11"
						(effects
							(font
								(size 1.27 1.27)
							)
						)
					)
				)
				(pin passive line
					(at 34.29 -6.35 180)
					(length 5.08)
					(hide yes)
					(name "VDD2H"
						(effects
							(font
								(size 1.27 1.27)
							)
						)
					)
					(number "K12"
						(effects
							(font
								(size 1.27 1.27)
							)
						)
					)
				)
				(pin passive line
					(at 34.29 -6.35 180)
					(length 5.08)
					(hide yes)
					(name "VDD2H"
						(effects
							(font
								(size 1.27 1.27)
							)
						)
					)
					(number "K13"
						(effects
							(font
								(size 1.27 1.27)
							)
						)
					)
				)
				(pin passive line
					(at 34.29 -6.35 180)
					(length 5.08)
					(hide yes)
					(name "VDD2H"
						(effects
							(font
								(size 1.27 1.27)
							)
						)
					)
					(number "K14"
						(effects
							(font
								(size 1.27 1.27)
							)
						)
					)
				)
				(pin passive line
					(at 34.29 -6.35 180)
					(length 5.08)
					(hide yes)
					(name "VDD2H"
						(effects
							(font
								(size 1.27 1.27)
							)
						)
					)
					(number "K15"
						(effects
							(font
								(size 1.27 1.27)
							)
						)
					)
				)
				(pin passive line
					(at 34.29 -6.35 180)
					(length 5.08)
					(hide yes)
					(name "VDD2H"
						(effects
							(font
								(size 1.27 1.27)
							)
						)
					)
					(number "K2"
						(effects
							(font
								(size 1.27 1.27)
							)
						)
					)
				)
				(pin passive line
					(at 34.29 -6.35 180)
					(length 5.08)
					(hide yes)
					(name "VDD2H"
						(effects
							(font
								(size 1.27 1.27)
							)
						)
					)
					(number "K3"
						(effects
							(font
								(size 1.27 1.27)
							)
						)
					)
				)
				(pin passive line
					(at 34.29 -6.35 180)
					(length 5.08)
					(hide yes)
					(name "VDD2H"
						(effects
							(font
								(size 1.27 1.27)
							)
						)
					)
					(number "K4"
						(effects
							(font
								(size 1.27 1.27)
							)
						)
					)
				)
				(pin passive line
					(at 34.29 -6.35 180)
					(length 5.08)
					(hide yes)
					(name "VDD2H"
						(effects
							(font
								(size 1.27 1.27)
							)
						)
					)
					(number "K5"
						(effects
							(font
								(size 1.27 1.27)
							)
						)
					)
				)
				(pin passive line
					(at 34.29 -6.35 180)
					(length 5.08)
					(hide yes)
					(name "VDD2H"
						(effects
							(font
								(size 1.27 1.27)
							)
						)
					)
					(number "K6"
						(effects
							(font
								(size 1.27 1.27)
							)
						)
					)
				)
				(pin passive line
					(at 34.29 -6.35 180)
					(length 5.08)
					(hide yes)
					(name "VDD2H"
						(effects
							(font
								(size 1.27 1.27)
							)
						)
					)
					(number "L10"
						(effects
							(font
								(size 1.27 1.27)
							)
						)
					)
				)
				(pin passive line
					(at 34.29 -6.35 180)
					(length 5.08)
					(hide yes)
					(name "VDD2H"
						(effects
							(font
								(size 1.27 1.27)
							)
						)
					)
					(number "L6"
						(effects
							(font
								(size 1.27 1.27)
							)
						)
					)
				)
				(pin passive line
					(at 34.29 -6.35 180)
					(length 5.08)
					(hide yes)
					(name "VDD2H"
						(effects
							(font
								(size 1.27 1.27)
							)
						)
					)
					(number "L7"
						(effects
							(font
								(size 1.27 1.27)
							)
						)
					)
				)
				(pin passive line
					(at 34.29 -6.35 180)
					(length 5.08)
					(hide yes)
					(name "VDD2H"
						(effects
							(font
								(size 1.27 1.27)
							)
						)
					)
					(number "L8"
						(effects
							(font
								(size 1.27 1.27)
							)
						)
					)
				)
				(pin passive line
					(at 34.29 -6.35 180)
					(length 5.08)
					(hide yes)
					(name "VDD2H"
						(effects
							(font
								(size 1.27 1.27)
							)
						)
					)
					(number "L9"
						(effects
							(font
								(size 1.27 1.27)
							)
						)
					)
				)
				(pin passive line
					(at 34.29 -6.35 180)
					(length 5.08)
					(hide yes)
					(name "VDD2H"
						(effects
							(font
								(size 1.27 1.27)
							)
						)
					)
					(number "M1"
						(effects
							(font
								(size 1.27 1.27)
							)
						)
					)
				)
				(pin passive line
					(at 34.29 -6.35 180)
					(length 5.08)
					(hide yes)
					(name "VDD2H"
						(effects
							(font
								(size 1.27 1.27)
							)
						)
					)
					(number "M10"
						(effects
							(font
								(size 1.27 1.27)
							)
						)
					)
				)
				(pin passive line
					(at 34.29 -6.35 180)
					(length 5.08)
					(hide yes)
					(name "VDD2H"
						(effects
							(font
								(size 1.27 1.27)
							)
						)
					)
					(number "M11"
						(effects
							(font
								(size 1.27 1.27)
							)
						)
					)
				)
				(pin passive line
					(at 34.29 -6.35 180)
					(length 5.08)
					(hide yes)
					(name "VDD2H"
						(effects
							(font
								(size 1.27 1.27)
							)
						)
					)
					(number "M12"
						(effects
							(font
								(size 1.27 1.27)
							)
						)
					)
				)
				(pin passive line
					(at 34.29 -6.35 180)
					(length 5.08)
					(hide yes)
					(name "VDD2H"
						(effects
							(font
								(size 1.27 1.27)
							)
						)
					)
					(number "M13"
						(effects
							(font
								(size 1.27 1.27)
							)
						)
					)
				)
				(pin passive line
					(at 34.29 -6.35 180)
					(length 5.08)
					(hide yes)
					(name "VDD2H"
						(effects
							(font
								(size 1.27 1.27)
							)
						)
					)
					(number "M14"
						(effects
							(font
								(size 1.27 1.27)
							)
						)
					)
				)
				(pin passive line
					(at 34.29 -6.35 180)
					(length 5.08)
					(hide yes)
					(name "VDD2H"
						(effects
							(font
								(size 1.27 1.27)
							)
						)
					)
					(number "M15"
						(effects
							(font
								(size 1.27 1.27)
							)
						)
					)
				)
				(pin passive line
					(at 34.29 -6.35 180)
					(length 5.08)
					(hide yes)
					(name "VDD2H"
						(effects
							(font
								(size 1.27 1.27)
							)
						)
					)
					(number "M2"
						(effects
							(font
								(size 1.27 1.27)
							)
						)
					)
				)
				(pin passive line
					(at 34.29 -6.35 180)
					(length 5.08)
					(hide yes)
					(name "VDD2H"
						(effects
							(font
								(size 1.27 1.27)
							)
						)
					)
					(number "M3"
						(effects
							(font
								(size 1.27 1.27)
							)
						)
					)
				)
				(pin passive line
					(at 34.29 -6.35 180)
					(length 5.08)
					(hide yes)
					(name "VDD2H"
						(effects
							(font
								(size 1.27 1.27)
							)
						)
					)
					(number "M4"
						(effects
							(font
								(size 1.27 1.27)
							)
						)
					)
				)
				(pin passive line
					(at 34.29 -6.35 180)
					(length 5.08)
					(hide yes)
					(name "VDD2H"
						(effects
							(font
								(size 1.27 1.27)
							)
						)
					)
					(number "M5"
						(effects
							(font
								(size 1.27 1.27)
							)
						)
					)
				)
				(pin passive line
					(at 34.29 -6.35 180)
					(length 5.08)
					(hide yes)
					(name "VDD2H"
						(effects
							(font
								(size 1.27 1.27)
							)
						)
					)
					(number "M6"
						(effects
							(font
								(size 1.27 1.27)
							)
						)
					)
				)
				(pin passive line
					(at 34.29 -6.35 180)
					(length 5.08)
					(hide yes)
					(name "VDD2H"
						(effects
							(font
								(size 1.27 1.27)
							)
						)
					)
					(number "N11"
						(effects
							(font
								(size 1.27 1.27)
							)
						)
					)
				)
				(pin passive line
					(at 34.29 -6.35 180)
					(length 5.08)
					(hide yes)
					(name "VDD2H"
						(effects
							(font
								(size 1.27 1.27)
							)
						)
					)
					(number "N5"
						(effects
							(font
								(size 1.27 1.27)
							)
						)
					)
				)
				(pin passive line
					(at 34.29 -6.35 180)
					(length 5.08)
					(hide yes)
					(name "VDD2H"
						(effects
							(font
								(size 1.27 1.27)
							)
						)
					)
					(number "T10"
						(effects
							(font
								(size 1.27 1.27)
							)
						)
					)
				)
				(pin passive line
					(at 34.29 -6.35 180)
					(length 5.08)
					(hide yes)
					(name "VDD2H"
						(effects
							(font
								(size 1.27 1.27)
							)
						)
					)
					(number "T6"
						(effects
							(font
								(size 1.27 1.27)
							)
						)
					)
				)
				(pin passive line
					(at 34.29 -6.35 180)
					(length 5.08)
					(hide yes)
					(name "VDD2H"
						(effects
							(font
								(size 1.27 1.27)
							)
						)
					)
					(number "T7"
						(effects
							(font
								(size 1.27 1.27)
							)
						)
					)
				)
				(pin passive line
					(at 34.29 -6.35 180)
					(length 5.08)
					(hide yes)
					(name "VDD2H"
						(effects
							(font
								(size 1.27 1.27)
							)
						)
					)
					(number "T9"
						(effects
							(font
								(size 1.27 1.27)
							)
						)
					)
				)
				(pin passive line
					(at 34.29 -6.35 180)
					(length 5.08)
					(hide yes)
					(name "VDD2H"
						(effects
							(font
								(size 1.27 1.27)
							)
						)
					)
					(number "U7"
						(effects
							(font
								(size 1.27 1.27)
							)
						)
					)
				)
				(pin passive line
					(at 34.29 -6.35 180)
					(length 5.08)
					(hide yes)
					(name "VDD2H"
						(effects
							(font
								(size 1.27 1.27)
							)
						)
					)
					(number "U9"
						(effects
							(font
								(size 1.27 1.27)
							)
						)
					)
				)
				(pin passive line
					(at 34.29 -6.35 180)
					(length 5.08)
					(hide yes)
					(name "VDD2H"
						(effects
							(font
								(size 1.27 1.27)
							)
						)
					)
					(number "V8"
						(effects
							(font
								(size 1.27 1.27)
							)
						)
					)
				)
				(pin passive line
					(at 34.29 -6.35 180)
					(length 5.08)
					(hide yes)
					(name "VDD2H"
						(effects
							(font
								(size 1.27 1.27)
							)
						)
					)
					(number "W7"
						(effects
							(font
								(size 1.27 1.27)
							)
						)
					)
				)
				(pin passive line
					(at 34.29 -6.35 180)
					(length 5.08)
					(hide yes)
					(name "VDD2H"
						(effects
							(font
								(size 1.27 1.27)
							)
						)
					)
					(number "W9"
						(effects
							(font
								(size 1.27 1.27)
							)
						)
					)
				)
				(pin passive line
					(at 34.29 -6.35 180)
					(length 5.08)
					(hide yes)
					(name "VDD2H"
						(effects
							(font
								(size 1.27 1.27)
							)
						)
					)
					(number "Y7"
						(effects
							(font
								(size 1.27 1.27)
							)
						)
					)
				)
				(pin passive line
					(at 34.29 -6.35 180)
					(length 5.08)
					(hide yes)
					(name "VDD2H"
						(effects
							(font
								(size 1.27 1.27)
							)
						)
					)
					(number "Y9"
						(effects
							(font
								(size 1.27 1.27)
							)
						)
					)
				)
				(pin passive line
					(at 34.29 -13.97 180)
					(length 5.08)
					(hide yes)
					(name "VDD2L"
						(effects
							(font
								(size 1.27 1.27)
							)
						)
					)
					(number "A10"
						(effects
							(font
								(size 1.27 1.27)
							)
						)
					)
				)
				(pin passive line
					(at 34.29 -13.97 180)
					(length 5.08)
					(name "VDD2L"
						(effects
							(font
								(size 1.27 1.27)
							)
						)
					)
					(number "A6"
						(effects
							(font
								(size 1.27 1.27)
							)
						)
					)
				)
				(pin passive line
					(at 34.29 -13.97 180)
					(length 5.08)
					(hide yes)
					(name "VDD2L"
						(effects
							(font
								(size 1.27 1.27)
							)
						)
					)
					(number "AA10"
						(effects
							(font
								(size 1.27 1.27)
							)
						)
					)
				)
				(pin passive line
					(at 34.29 -13.97 180)
					(length 5.08)
					(hide yes)
					(name "VDD2L"
						(effects
							(font
								(size 1.27 1.27)
							)
						)
					)
					(number "AA6"
						(effects
							(font
								(size 1.27 1.27)
							)
						)
					)
				)
				(pin passive line
					(at 34.29 -13.97 180)
					(length 5.08)
					(hide yes)
					(name "VDD2L"
						(effects
							(font
								(size 1.27 1.27)
							)
						)
					)
					(number "B10"
						(effects
							(font
								(size 1.27 1.27)
							)
						)
					)
				)
				(pin passive line
					(at 34.29 -13.97 180)
					(length 5.08)
					(hide yes)
					(name "VDD2L"
						(effects
							(font
								(size 1.27 1.27)
							)
						)
					)
					(number "B6"
						(effects
							(font
								(size 1.27 1.27)
							)
						)
					)
				)
				(pin passive line
					(at 34.29 -13.97 180)
					(length 5.08)
					(hide yes)
					(name "VDD2L"
						(effects
							(font
								(size 1.27 1.27)
							)
						)
					)
					(number "H14"
						(effects
							(font
								(size 1.27 1.27)
							)
						)
					)
				)
				(pin passive line
					(at 34.29 -13.97 180)
					(length 5.08)
					(hide yes)
					(name "VDD2L"
						(effects
							(font
								(size 1.27 1.27)
							)
						)
					)
					(number "H2"
						(effects
							(font
								(size 1.27 1.27)
							)
						)
					)
				)
				(pin passive line
					(at 34.29 -13.97 180)
					(length 5.08)
					(hide yes)
					(name "VDD2L"
						(effects
							(font
								(size 1.27 1.27)
							)
						)
					)
					(number "J14"
						(effects
							(font
								(size 1.27 1.27)
							)
						)
					)
				)
				(pin passive line
					(at 34.29 -13.97 180)
					(length 5.08)
					(hide yes)
					(name "VDD2L"
						(effects
							(font
								(size 1.27 1.27)
							)
						)
					)
					(number "J2"
						(effects
							(font
								(size 1.27 1.27)
							)
						)
					)
				)
				(pin passive line
					(at 34.29 -13.97 180)
					(length 5.08)
					(hide yes)
					(name "VDD2L"
						(effects
							(font
								(size 1.27 1.27)
							)
						)
					)
					(number "N14"
						(effects
							(font
								(size 1.27 1.27)
							)
						)
					)
				)
				(pin passive line
					(at 34.29 -13.97 180)
					(length 5.08)
					(hide yes)
					(name "VDD2L"
						(effects
							(font
								(size 1.27 1.27)
							)
						)
					)
					(number "N2"
						(effects
							(font
								(size 1.27 1.27)
							)
						)
					)
				)
				(pin passive line
					(at 34.29 -13.97 180)
					(length 5.08)
					(hide yes)
					(name "VDD2L"
						(effects
							(font
								(size 1.27 1.27)
							)
						)
					)
					(number "P14"
						(effects
							(font
								(size 1.27 1.27)
							)
						)
					)
				)
				(pin passive line
					(at 34.29 -13.97 180)
					(length 5.08)
					(hide yes)
					(name "VDD2L"
						(effects
							(font
								(size 1.27 1.27)
							)
						)
					)
					(number "P2"
						(effects
							(font
								(size 1.27 1.27)
							)
						)
					)
				)
				(pin passive line
					(at 34.29 -13.97 180)
					(length 5.08)
					(hide yes)
					(name "VDD2L"
						(effects
							(font
								(size 1.27 1.27)
							)
						)
					)
					(number "Y10"
						(effects
							(font
								(size 1.27 1.27)
							)
						)
					)
				)
				(pin passive line
					(at 34.29 -13.97 180)
					(length 5.08)
					(hide yes)
					(name "VDD2L"
						(effects
							(font
								(size 1.27 1.27)
							)
						)
					)
					(number "Y6"
						(effects
							(font
								(size 1.27 1.27)
							)
						)
					)
				)
			)
			(symbol "MT62F1G32D4DR-031_1_1"
				(rectangle
					(start 5.08 2.54)
					(end 29.21 -33.02)
					(stroke
						(width 0)
						(type default)
					)
					(fill
						(type background)
					)
				)
			)
			(symbol "MT62F1G32D4DR-031_2_0"
				(pin passive line
					(at 0 0 0)
					(length 5.08)
					(name "CS0_A"
						(effects
							(font
								(size 1.27 1.27)
							)
						)
					)
					(number "H7"
						(effects
							(font
								(size 1.27 1.27)
							)
						)
					)
				)
				(pin passive line
					(at 0 -2.54 0)
					(length 5.08)
					(name "CS1_A"
						(effects
							(font
								(size 1.27 1.27)
							)
						)
					)
					(number "G6"
						(effects
							(font
								(size 1.27 1.27)
							)
						)
					)
				)
				(pin passive line
					(at 0 -7.62 0)
					(length 5.08)
					(name "DMI0_A"
						(effects
							(font
								(size 1.27 1.27)
							)
						)
					)
					(number "A4"
						(effects
							(font
								(size 1.27 1.27)
							)
						)
					)
				)
				(pin passive line
					(at 0 -10.16 0)
					(length 5.08)
					(name "DMI1_A"
						(effects
							(font
								(size 1.27 1.27)
							)
						)
					)
					(number "A12"
						(effects
							(font
								(size 1.27 1.27)
							)
						)
					)
				)
				(pin passive line
					(at 0 -15.24 0)
					(length 5.08)
					(name "WCK0_t_A"
						(effects
							(font
								(size 1.27 1.27)
							)
						)
					)
					(number "E4"
						(effects
							(font
								(size 1.27 1.27)
							)
						)
					)
				)
				(pin passive line
					(at 0 -17.78 0)
					(length 5.08)
					(name "WCK0_c_A"
						(effects
							(font
								(size 1.27 1.27)
							)
						)
					)
					(number "D5"
						(effects
							(font
								(size 1.27 1.27)
							)
						)
					)
				)
				(pin passive line
					(at 0 -22.86 0)
					(length 5.08)
					(name "WCK1_t_A"
						(effects
							(font
								(size 1.27 1.27)
							)
						)
					)
					(number "E12"
						(effects
							(font
								(size 1.27 1.27)
							)
						)
					)
				)
				(pin passive line
					(at 0 -25.4 0)
					(length 5.08)
					(name "WCK1_c_A"
						(effects
							(font
								(size 1.27 1.27)
							)
						)
					)
					(number "D11"
						(effects
							(font
								(size 1.27 1.27)
							)
						)
					)
				)
				(pin passive line
					(at 0 -30.48 0)
					(length 5.08)
					(name "CK_t_A"
						(effects
							(font
								(size 1.27 1.27)
							)
						)
					)
					(number "H9"
						(effects
							(font
								(size 1.27 1.27)
							)
						)
					)
				)
				(pin passive line
					(at 0 -33.02 0)
					(length 5.08)
					(name "CK_c_A"
						(effects
							(font
								(size 1.27 1.27)
							)
						)
					)
					(number "J9"
						(effects
							(font
								(size 1.27 1.27)
							)
						)
					)
				)
				(pin passive line
					(at 0 -38.1 0)
					(length 5.08)
					(name "CA0_A"
						(effects
							(font
								(size 1.27 1.27)
							)
						)
					)
					(number "G4"
						(effects
							(font
								(size 1.27 1.27)
							)
						)
					)
				)
				(pin passive line
					(at 0 -40.64 0)
					(length 5.08)
					(name "CA1_A"
						(effects
							(font
								(size 1.27 1.27)
							)
						)
					)
					(number "H5"
						(effects
							(font
								(size 1.27 1.27)
							)
						)
					)
				)
				(pin passive line
					(at 0 -43.18 0)
					(length 5.08)
					(name "CA2_A"
						(effects
							(font
								(size 1.27 1.27)
							)
						)
					)
					(number "G8"
						(effects
							(font
								(size 1.27 1.27)
							)
						)
					)
				)
				(pin passive line
					(at 0 -45.72 0)
					(length 5.08)
					(name "CA3_A"
						(effects
							(font
								(size 1.27 1.27)
							)
						)
					)
					(number "H11"
						(effects
							(font
								(size 1.27 1.27)
							)
						)
					)
				)
				(pin passive line
					(at 0 -48.26 0)
					(length 5.08)
					(name "CA4_A"
						(effects
							(font
								(size 1.27 1.27)
							)
						)
					)
					(number "G10"
						(effects
							(font
								(size 1.27 1.27)
							)
						)
					)
				)
				(pin passive line
					(at 0 -50.8 0)
					(length 5.08)
					(name "CA5_A"
						(effects
							(font
								(size 1.27 1.27)
							)
						)
					)
					(number "H13"
						(effects
							(font
								(size 1.27 1.27)
							)
						)
					)
				)
				(pin passive line
					(at 0 -53.34 0)
					(length 5.08)
					(name "CA6_A"
						(effects
							(font
								(size 1.27 1.27)
							)
						)
					)
					(number "G12"
						(effects
							(font
								(size 1.27 1.27)
							)
						)
					)
				)
				(pin passive line
					(at 34.29 0 180)
					(length 5.08)
					(name "RDQS0_t_A"
						(effects
							(font
								(size 1.27 1.27)
							)
						)
					)
					(number "B3"
						(effects
							(font
								(size 1.27 1.27)
							)
						)
					)
				)
				(pin passive line
					(at 34.29 -2.54 180)
					(length 5.08)
					(name "RDQS0_c_A"
						(effects
							(font
								(size 1.27 1.27)
							)
						)
					)
					(number "C4"
						(effects
							(font
								(size 1.27 1.27)
							)
						)
					)
				)
				(pin passive line
					(at 34.29 -7.62 180)
					(length 5.08)
					(name "RDQS1_t_A"
						(effects
							(font
								(size 1.27 1.27)
							)
						)
					)
					(number "B13"
						(effects
							(font
								(size 1.27 1.27)
							)
						)
					)
				)
				(pin passive line
					(at 34.29 -10.16 180)
					(length 5.08)
					(name "RDQS1_c_A"
						(effects
							(font
								(size 1.27 1.27)
							)
						)
					)
					(number "C12"
						(effects
							(font
								(size 1.27 1.27)
							)
						)
					)
				)
				(pin passive line
					(at 34.29 -15.24 180)
					(length 5.08)
					(name "DQ0_A"
						(effects
							(font
								(size 1.27 1.27)
							)
						)
					)
					(number "D1"
						(effects
							(font
								(size 1.27 1.27)
							)
						)
					)
				)
				(pin passive line
					(at 34.29 -17.78 180)
					(length 5.08)
					(name "DQ1_A"
						(effects
							(font
								(size 1.27 1.27)
							)
						)
					)
					(number "C2"
						(effects
							(font
								(size 1.27 1.27)
							)
						)
					)
				)
				(pin passive line
					(at 34.29 -20.32 180)
					(length 5.08)
					(name "DQ2_A"
						(effects
							(font
								(size 1.27 1.27)
							)
						)
					)
					(number "E2"
						(effects
							(font
								(size 1.27 1.27)
							)
						)
					)
				)
				(pin passive line
					(at 34.29 -22.86 180)
					(length 5.08)
					(name "DQ3_A"
						(effects
							(font
								(size 1.27 1.27)
							)
						)
					)
					(number "D3"
						(effects
							(font
								(size 1.27 1.27)
							)
						)
					)
				)
				(pin passive line
					(at 34.29 -25.4 180)
					(length 5.08)
					(name "DQ4_A"
						(effects
							(font
								(size 1.27 1.27)
							)
						)
					)
					(number "B5"
						(effects
							(font
								(size 1.27 1.27)
							)
						)
					)
				)
				(pin passive line
					(at 34.29 -27.94 180)
					(length 5.08)
					(name "DQ5_A"
						(effects
							(font
								(size 1.27 1.27)
							)
						)
					)
					(number "C6"
						(effects
							(font
								(size 1.27 1.27)
							)
						)
					)
				)
				(pin passive line
					(at 34.29 -30.48 180)
					(length 5.08)
					(name "DQ6_A"
						(effects
							(font
								(size 1.27 1.27)
							)
						)
					)
					(number "E6"
						(effects
							(font
								(size 1.27 1.27)
							)
						)
					)
				)
				(pin passive line
					(at 34.29 -33.02 180)
					(length 5.08)
					(name "DQ7_A"
						(effects
							(font
								(size 1.27 1.27)
							)
						)
					)
					(number "F5"
						(effects
							(font
								(size 1.27 1.27)
							)
						)
					)
				)
				(pin passive line
					(at 34.29 -35.56 180)
					(length 5.08)
					(name "DQ8_A"
						(effects
							(font
								(size 1.27 1.27)
							)
						)
					)
					(number "D15"
						(effects
							(font
								(size 1.27 1.27)
							)
						)
					)
				)
				(pin passive line
					(at 34.29 -38.1 180)
					(length 5.08)
					(name "DQ9_A"
						(effects
							(font
								(size 1.27 1.27)
							)
						)
					)
					(number "C14"
						(effects
							(font
								(size 1.27 1.27)
							)
						)
					)
				)
				(pin passive line
					(at 34.29 -40.64 180)
					(length 5.08)
					(name "DQ10_A"
						(effects
							(font
								(size 1.27 1.27)
							)
						)
					)
					(number "E14"
						(effects
							(font
								(size 1.27 1.27)
							)
						)
					)
				)
				(pin passive line
					(at 34.29 -43.18 180)
					(length 5.08)
					(name "DQ11_A"
						(effects
							(font
								(size 1.27 1.27)
							)
						)
					)
					(number "D13"
						(effects
							(font
								(size 1.27 1.27)
							)
						)
					)
				)
				(pin passive line
					(at 34.29 -45.72 180)
					(length 5.08)
					(name "DQ12_A"
						(effects
							(font
								(size 1.27 1.27)
							)
						)
					)
					(number "B11"
						(effects
							(font
								(size 1.27 1.27)
							)
						)
					)
				)
				(pin passive line
					(at 34.29 -48.26 180)
					(length 5.08)
					(name "DQ13_A"
						(effects
							(font
								(size 1.27 1.27)
							)
						)
					)
					(number "C10"
						(effects
							(font
								(size 1.27 1.27)
							)
						)
					)
				)
				(pin passive line
					(at 34.29 -50.8 180)
					(length 5.08)
					(name "DQ14_A"
						(effects
							(font
								(size 1.27 1.27)
							)
						)
					)
					(number "E10"
						(effects
							(font
								(size 1.27 1.27)
							)
						)
					)
				)
				(pin passive line
					(at 34.29 -53.34 180)
					(length 5.08)
					(name "DQ15_A"
						(effects
							(font
								(size 1.27 1.27)
							)
						)
					)
					(number "F11"
						(effects
							(font
								(size 1.27 1.27)
							)
						)
					)
				)
			)
			(symbol "MT62F1G32D4DR-031_2_1"
				(rectangle
					(start 5.08 2.54)
					(end 29.21 -55.88)
					(stroke
						(width 0)
						(type default)
					)
					(fill
						(type background)
					)
				)
			)
			(symbol "MT62F1G32D4DR-031_3_0"
				(pin passive line
					(at 0 0 0)
					(length 5.08)
					(name "CS0_B"
						(effects
							(font
								(size 1.27 1.27)
							)
						)
					)
					(number "P9"
						(effects
							(font
								(size 1.27 1.27)
							)
						)
					)
				)
				(pin passive line
					(at 0 -2.54 0)
					(length 5.08)
					(name "CS1_B"
						(effects
							(font
								(size 1.27 1.27)
							)
						)
					)
					(number "R10"
						(effects
							(font
								(size 1.27 1.27)
							)
						)
					)
				)
				(pin passive line
					(at 0 -7.62 0)
					(length 5.08)
					(name "DMI0_B"
						(effects
							(font
								(size 1.27 1.27)
							)
						)
					)
					(number "AA12"
						(effects
							(font
								(size 1.27 1.27)
							)
						)
					)
				)
				(pin passive line
					(at 0 -10.16 0)
					(length 5.08)
					(name "DMI1_B"
						(effects
							(font
								(size 1.27 1.27)
							)
						)
					)
					(number "AA4"
						(effects
							(font
								(size 1.27 1.27)
							)
						)
					)
				)
				(pin passive line
					(at 0 -15.24 0)
					(length 5.08)
					(name "WCK0_t_B"
						(effects
							(font
								(size 1.27 1.27)
							)
						)
					)
					(number "U12"
						(effects
							(font
								(size 1.27 1.27)
							)
						)
					)
				)
				(pin passive line
					(at 0 -17.78 0)
					(length 5.08)
					(name "WCK0_c_B"
						(effects
							(font
								(size 1.27 1.27)
							)
						)
					)
					(number "V11"
						(effects
							(font
								(size 1.27 1.27)
							)
						)
					)
				)
				(pin passive line
					(at 0 -22.86 0)
					(length 5.08)
					(name "WCK1_t_B"
						(effects
							(font
								(size 1.27 1.27)
							)
						)
					)
					(number "U4"
						(effects
							(font
								(size 1.27 1.27)
							)
						)
					)
				)
				(pin passive line
					(at 0 -25.4 0)
					(length 5.08)
					(name "WCK1_c_B"
						(effects
							(font
								(size 1.27 1.27)
							)
						)
					)
					(number "V5"
						(effects
							(font
								(size 1.27 1.27)
							)
						)
					)
				)
				(pin passive line
					(at 0 -30.48 0)
					(length 5.08)
					(name "CK_t_B"
						(effects
							(font
								(size 1.27 1.27)
							)
						)
					)
					(number "P7"
						(effects
							(font
								(size 1.27 1.27)
							)
						)
					)
				)
				(pin passive line
					(at 0 -33.02 0)
					(length 5.08)
					(name "CK_c_B"
						(effects
							(font
								(size 1.27 1.27)
							)
						)
					)
					(number "N7"
						(effects
							(font
								(size 1.27 1.27)
							)
						)
					)
				)
				(pin passive line
					(at 0 -38.1 0)
					(length 5.08)
					(name "CA0_B"
						(effects
							(font
								(size 1.27 1.27)
							)
						)
					)
					(number "R12"
						(effects
							(font
								(size 1.27 1.27)
							)
						)
					)
				)
				(pin passive line
					(at 0 -40.64 0)
					(length 5.08)
					(name "CA1_B"
						(effects
							(font
								(size 1.27 1.27)
							)
						)
					)
					(number "P11"
						(effects
							(font
								(size 1.27 1.27)
							)
						)
					)
				)
				(pin passive line
					(at 0 -43.18 0)
					(length 5.08)
					(name "CA2_B"
						(effects
							(font
								(size 1.27 1.27)
							)
						)
					)
					(number "R8"
						(effects
							(font
								(size 1.27 1.27)
							)
						)
					)
				)
				(pin passive line
					(at 0 -45.72 0)
					(length 5.08)
					(name "CA3_B"
						(effects
							(font
								(size 1.27 1.27)
							)
						)
					)
					(number "P5"
						(effects
							(font
								(size 1.27 1.27)
							)
						)
					)
				)
				(pin passive line
					(at 0 -48.26 0)
					(length 5.08)
					(name "CA4_B"
						(effects
							(font
								(size 1.27 1.27)
							)
						)
					)
					(number "R6"
						(effects
							(font
								(size 1.27 1.27)
							)
						)
					)
				)
				(pin passive line
					(at 0 -50.8 0)
					(length 5.08)
					(name "CA5_B"
						(effects
							(font
								(size 1.27 1.27)
							)
						)
					)
					(number "P3"
						(effects
							(font
								(size 1.27 1.27)
							)
						)
					)
				)
				(pin passive line
					(at 0 -53.34 0)
					(length 5.08)
					(name "CA6_B"
						(effects
							(font
								(size 1.27 1.27)
							)
						)
					)
					(number "R4"
						(effects
							(font
								(size 1.27 1.27)
							)
						)
					)
				)
				(pin passive line
					(at 34.29 0 180)
					(length 5.08)
					(name "RDQS0_t_B"
						(effects
							(font
								(size 1.27 1.27)
							)
						)
					)
					(number "Y13"
						(effects
							(font
								(size 1.27 1.27)
							)
						)
					)
				)
				(pin passive line
					(at 34.29 -2.54 180)
					(length 5.08)
					(name "RDQS0_c_B"
						(effects
							(font
								(size 1.27 1.27)
							)
						)
					)
					(number "W12"
						(effects
							(font
								(size 1.27 1.27)
							)
						)
					)
				)
				(pin passive line
					(at 34.29 -7.62 180)
					(length 5.08)
					(name "RDQS1_t_B"
						(effects
							(font
								(size 1.27 1.27)
							)
						)
					)
					(number "Y3"
						(effects
							(font
								(size 1.27 1.27)
							)
						)
					)
				)
				(pin passive line
					(at 34.29 -10.16 180)
					(length 5.08)
					(name "RDQS1_c_B"
						(effects
							(font
								(size 1.27 1.27)
							)
						)
					)
					(number "W4"
						(effects
							(font
								(size 1.27 1.27)
							)
						)
					)
				)
				(pin passive line
					(at 34.29 -15.24 180)
					(length 5.08)
					(name "DQ0_B"
						(effects
							(font
								(size 1.27 1.27)
							)
						)
					)
					(number "V15"
						(effects
							(font
								(size 1.27 1.27)
							)
						)
					)
				)
				(pin passive line
					(at 34.29 -17.78 180)
					(length 5.08)
					(name "DQ1_B"
						(effects
							(font
								(size 1.27 1.27)
							)
						)
					)
					(number "W14"
						(effects
							(font
								(size 1.27 1.27)
							)
						)
					)
				)
				(pin passive line
					(at 34.29 -20.32 180)
					(length 5.08)
					(name "DQ2_B"
						(effects
							(font
								(size 1.27 1.27)
							)
						)
					)
					(number "U14"
						(effects
							(font
								(size 1.27 1.27)
							)
						)
					)
				)
				(pin passive line
					(at 34.29 -22.86 180)
					(length 5.08)
					(name "DQ3_B"
						(effects
							(font
								(size 1.27 1.27)
							)
						)
					)
					(number "V13"
						(effects
							(font
								(size 1.27 1.27)
							)
						)
					)
				)
				(pin passive line
					(at 34.29 -25.4 180)
					(length 5.08)
					(name "DQ4_B"
						(effects
							(font
								(size 1.27 1.27)
							)
						)
					)
					(number "Y11"
						(effects
							(font
								(size 1.27 1.27)
							)
						)
					)
				)
				(pin passive line
					(at 34.29 -27.94 180)
					(length 5.08)
					(name "DQ5_B"
						(effects
							(font
								(size 1.27 1.27)
							)
						)
					)
					(number "W10"
						(effects
							(font
								(size 1.27 1.27)
							)
						)
					)
				)
				(pin passive line
					(at 34.29 -30.48 180)
					(length 5.08)
					(name "DQ6_B"
						(effects
							(font
								(size 1.27 1.27)
							)
						)
					)
					(number "U10"
						(effects
							(font
								(size 1.27 1.27)
							)
						)
					)
				)
				(pin passive line
					(at 34.29 -33.02 180)
					(length 5.08)
					(name "DQ7_B"
						(effects
							(font
								(size 1.27 1.27)
							)
						)
					)
					(number "T11"
						(effects
							(font
								(size 1.27 1.27)
							)
						)
					)
				)
				(pin passive line
					(at 34.29 -35.56 180)
					(length 5.08)
					(name "DQ8_B"
						(effects
							(font
								(size 1.27 1.27)
							)
						)
					)
					(number "V1"
						(effects
							(font
								(size 1.27 1.27)
							)
						)
					)
				)
				(pin passive line
					(at 34.29 -38.1 180)
					(length 5.08)
					(name "DQ9_B"
						(effects
							(font
								(size 1.27 1.27)
							)
						)
					)
					(number "W2"
						(effects
							(font
								(size 1.27 1.27)
							)
						)
					)
				)
				(pin passive line
					(at 34.29 -40.64 180)
					(length 5.08)
					(name "DQ10_B"
						(effects
							(font
								(size 1.27 1.27)
							)
						)
					)
					(number "U2"
						(effects
							(font
								(size 1.27 1.27)
							)
						)
					)
				)
				(pin passive line
					(at 34.29 -43.18 180)
					(length 5.08)
					(name "DQ11_B"
						(effects
							(font
								(size 1.27 1.27)
							)
						)
					)
					(number "V3"
						(effects
							(font
								(size 1.27 1.27)
							)
						)
					)
				)
				(pin passive line
					(at 34.29 -45.72 180)
					(length 5.08)
					(name "DQ12_B"
						(effects
							(font
								(size 1.27 1.27)
							)
						)
					)
					(number "Y5"
						(effects
							(font
								(size 1.27 1.27)
							)
						)
					)
				)
				(pin passive line
					(at 34.29 -48.26 180)
					(length 5.08)
					(name "DQ13_B"
						(effects
							(font
								(size 1.27 1.27)
							)
						)
					)
					(number "W6"
						(effects
							(font
								(size 1.27 1.27)
							)
						)
					)
				)
				(pin passive line
					(at 34.29 -50.8 180)
					(length 5.08)
					(name "DQ14_B"
						(effects
							(font
								(size 1.27 1.27)
							)
						)
					)
					(number "U6"
						(effects
							(font
								(size 1.27 1.27)
							)
						)
					)
				)
				(pin passive line
					(at 34.29 -53.34 180)
					(length 5.08)
					(name "DQ15_B"
						(effects
							(font
								(size 1.27 1.27)
							)
						)
					)
					(number "T5"
						(effects
							(font
								(size 1.27 1.27)
							)
						)
					)
				)
			)
			(symbol "MT62F1G32D4DR-031_3_1"
				(rectangle
					(start 5.08 2.54)
					(end 29.21 -55.88)
					(stroke
						(width 0)
						(type default)
					)
					(fill
						(type background)
					)
				)
			)
		)
	(symbol "antmicroPMICVoltageRegulatorsDCDCSwitchingRegulators:MPM54304GMN-0001"
			(exclude_from_sim no)
			(in_bom yes)
			(on_board yes)
			(property "Reference" "U"
				(at 46.99 -2.54 0)
				(effects
					(font
						(size 1.27 1.27)
						(thickness 0.15)
					)
					(justify left bottom)
				)
			)
			(property "Value" "MPM54304GMN-0001"
				(at 46.99 -5.08 0)
				(effects
					(font
						(size 1.27 1.27)
						(thickness 0.15)
					)
					(justify left bottom)
				)
			)
			(property "Footprint" "antmicro-footprints:LGA-33_7x7mm_P0.65mm"
				(at 46.99 -7.62 0)
				(effects
					(font
						(size 1.27 1.27)
						(thickness 0.15)
					)
					(justify left bottom)
					(hide yes)
				)
			)
			(property "Datasheet" "https://www.monolithicpower.com/en/documentview/productdocument/index/version/2/document_type/Datasheet/lang/en/sku/MPM54304/document_id/4982/"
				(at 46.99 -10.16 0)
				(effects
					(font
						(size 1.27 1.27)
						(thickness 0.15)
					)
					(justify left bottom)
					(hide yes)
				)
			)
			(property "Description" "DC-DC Switching Synchronous Step-Down Regulator, Multi Output, 4-16V in, 1V/3.3V, 4.2/3A out, LGA33"
				(at 0 0 0)
				(effects
					(font
						(size 1.27 1.27)
					)
					(hide yes)
				)
			)
			(property "MPN" "MPM54304GMN-0001"
				(at 46.99 -12.7 0)
				(effects
					(font
						(size 1.27 1.27)
					)
					(justify left bottom)
					(hide yes)
				)
			)
			(property "Manufacturer" "Monolithic Power Systems"
				(at 46.99 -15.24 0)
				(effects
					(font
						(size 1.27 1.27)
					)
					(justify left bottom)
					(hide yes)
				)
			)
			(property "Author" "Antmicro"
				(at 46.99 -17.78 0)
				(effects
					(font
						(size 1.27 1.27)
					)
					(justify left bottom)
					(hide yes)
				)
			)
			(property "License" "Apache-2.0"
				(at 46.99 -20.32 0)
				(effects
					(font
						(size 1.27 1.27)
					)
					(justify left bottom)
					(hide yes)
				)
			)
			(property "ki_keywords" "SMT, PMIC, IC, VOLTAGE, REGULATOR, SWITCHING, DC-DC"
				(at 0 0 0)
				(effects
					(font
						(size 1.27 1.27)
					)
					(hide yes)
				)
			)
			(property "ki_fp_filters" "CP_48_13_ADI CP_48_13_ADI-M CP_48_13_ADI-L"
				(at 0 0 0)
				(effects
					(font
						(size 1.27 1.27)
					)
					(hide yes)
				)
			)
			(symbol "MPM54304GMN-0001_1_1"
				(rectangle
					(start 2.54 3.81)
					(end 2.54 3.81)
					(stroke
						(width 0.254)
						(type default)
					)
					(fill
						(type background)
					)
				)
				(rectangle
					(start 2.54 2.54)
					(end 25.4 -38.1)
					(stroke
						(width 0.254)
						(type default)
					)
					(fill
						(type background)
					)
				)
				(polyline
					(pts
						(xy 25.4 1.27) (xy 17.78 1.27) (xy 17.78 -8.89) (xy 25.4 -8.89)
					)
					(stroke
						(width 0.254)
						(type default)
					)
					(fill
						(type background)
					)
				)
				(polyline
					(pts
						(xy 25.4 -11.43) (xy 17.78 -11.43) (xy 17.78 -19.05) (xy 25.4 -19.05)
					)
					(stroke
						(width 0.254)
						(type default)
					)
					(fill
						(type background)
					)
				)
				(polyline
					(pts
						(xy 25.4 -21.59) (xy 17.78 -21.59) (xy 17.78 -29.21) (xy 25.4 -29.21)
					)
					(stroke
						(width 0.254)
						(type default)
					)
					(fill
						(type background)
					)
				)
				(polyline
					(pts
						(xy 25.4 -31.75) (xy 17.78 -31.75) (xy 17.78 -36.83) (xy 25.4 -36.83)
					)
					(stroke
						(width 0.254)
						(type default)
					)
					(fill
						(type background)
					)
				)
				(pin input line
					(at 0 0 0)
					(length 2.54)
					(name "VIN"
						(effects
							(font
								(size 1.27 1.27)
							)
						)
					)
					(number "28"
						(effects
							(font
								(size 1.27 1.27)
							)
						)
					)
				)
				(pin passive line
					(at 0 0 0)
					(length 2.54)
					(hide yes)
					(name "VIN"
						(effects
							(font
								(size 1.27 1.27)
							)
						)
					)
					(number "29"
						(effects
							(font
								(size 1.27 1.27)
							)
						)
					)
				)
				(pin input line
					(at 0 -2.54 0)
					(length 2.54)
					(name "VCC"
						(effects
							(font
								(size 1.27 1.27)
							)
						)
					)
					(number "25"
						(effects
							(font
								(size 1.27 1.27)
							)
						)
					)
				)
				(pin input line
					(at 0 -10.16 0)
					(length 2.54)
					(name "EN/SYNCI"
						(effects
							(font
								(size 1.27 1.27)
							)
						)
					)
					(number "19"
						(effects
							(font
								(size 1.27 1.27)
							)
						)
					)
				)
				(pin bidirectional line
					(at 0 -19.05 0)
					(length 2.54)
					(name "SDA"
						(effects
							(font
								(size 1.27 1.27)
							)
						)
					)
					(number "3"
						(effects
							(font
								(size 1.27 1.27)
							)
						)
					)
				)
				(pin input line
					(at 0 -21.59 0)
					(length 2.54)
					(name "SCL"
						(effects
							(font
								(size 1.27 1.27)
							)
						)
					)
					(number "4"
						(effects
							(font
								(size 1.27 1.27)
							)
						)
					)
				)
				(pin input line
					(at 0 -30.48 0)
					(length 2.54)
					(name "GPIO"
						(effects
							(font
								(size 1.27 1.27)
							)
						)
					)
					(number "26"
						(effects
							(font
								(size 1.27 1.27)
							)
						)
					)
				)
				(pin passive line
					(at 0 -35.56 0)
					(length 2.54)
					(name "GND"
						(effects
							(font
								(size 1.27 1.27)
							)
						)
					)
					(number "10"
						(effects
							(font
								(size 1.27 1.27)
							)
						)
					)
				)
				(pin passive line
					(at 0 -35.56 0)
					(length 2.54)
					(hide yes)
					(name "GND"
						(effects
							(font
								(size 1.27 1.27)
							)
						)
					)
					(number "13"
						(effects
							(font
								(size 1.27 1.27)
							)
						)
					)
				)
				(pin passive line
					(at 0 -35.56 0)
					(length 2.54)
					(hide yes)
					(name "GND"
						(effects
							(font
								(size 1.27 1.27)
							)
						)
					)
					(number "16"
						(effects
							(font
								(size 1.27 1.27)
							)
						)
					)
				)
				(pin passive line
					(at 0 -35.56 0)
					(length 2.54)
					(hide yes)
					(name "GND"
						(effects
							(font
								(size 1.27 1.27)
							)
						)
					)
					(number "2"
						(effects
							(font
								(size 1.27 1.27)
							)
						)
					)
				)
				(pin passive line
					(at 0 -35.56 0)
					(length 2.54)
					(hide yes)
					(name "GND"
						(effects
							(font
								(size 1.27 1.27)
							)
						)
					)
					(number "20"
						(effects
							(font
								(size 1.27 1.27)
							)
						)
					)
				)
				(pin passive line
					(at 0 -35.56 0)
					(length 2.54)
					(hide yes)
					(name "GND"
						(effects
							(font
								(size 1.27 1.27)
							)
						)
					)
					(number "21"
						(effects
							(font
								(size 1.27 1.27)
							)
						)
					)
				)
				(pin passive line
					(at 0 -35.56 0)
					(length 2.54)
					(hide yes)
					(name "GND"
						(effects
							(font
								(size 1.27 1.27)
							)
						)
					)
					(number "27"
						(effects
							(font
								(size 1.27 1.27)
							)
						)
					)
				)
				(pin passive line
					(at 0 -35.56 0)
					(length 2.54)
					(hide yes)
					(name "GND"
						(effects
							(font
								(size 1.27 1.27)
							)
						)
					)
					(number "33"
						(effects
							(font
								(size 1.27 1.27)
							)
						)
					)
				)
				(pin passive line
					(at 0 -35.56 0)
					(length 2.54)
					(hide yes)
					(name "GND"
						(effects
							(font
								(size 1.27 1.27)
							)
						)
					)
					(number "5"
						(effects
							(font
								(size 1.27 1.27)
							)
						)
					)
				)
				(pin passive line
					(at 0 -35.56 0)
					(length 2.54)
					(hide yes)
					(name "GND"
						(effects
							(font
								(size 1.27 1.27)
							)
						)
					)
					(number "7"
						(effects
							(font
								(size 1.27 1.27)
							)
						)
					)
				)
				(pin power_out line
					(at 27.94 0 180)
					(length 2.54)
					(name "VOUT1"
						(effects
							(font
								(size 1.27 1.27)
							)
						)
					)
					(number "14"
						(effects
							(font
								(size 1.27 1.27)
							)
						)
					)
				)
				(pin passive line
					(at 27.94 0 180)
					(length 2.54)
					(hide yes)
					(name "VOUT1"
						(effects
							(font
								(size 1.27 1.27)
							)
						)
					)
					(number "15"
						(effects
							(font
								(size 1.27 1.27)
							)
						)
					)
				)
				(pin power_out line
					(at 27.94 -2.54 180)
					(length 2.54)
					(name "SW1"
						(effects
							(font
								(size 1.27 1.27)
							)
						)
					)
					(number "12"
						(effects
							(font
								(size 1.27 1.27)
							)
						)
					)
				)
				(pin input line
					(at 27.94 -5.08 180)
					(length 2.54)
					(name "FB1"
						(effects
							(font
								(size 1.27 1.27)
							)
						)
					)
					(number "18"
						(effects
							(font
								(size 1.27 1.27)
							)
						)
					)
				)
				(pin power_out line
					(at 27.94 -7.62 180)
					(length 2.54)
					(name "SGND1"
						(effects
							(font
								(size 1.27 1.27)
							)
						)
					)
					(number "17"
						(effects
							(font
								(size 1.27 1.27)
							)
						)
					)
				)
				(pin power_out line
					(at 27.94 -12.7 180)
					(length 2.54)
					(name "VOUT2"
						(effects
							(font
								(size 1.27 1.27)
							)
						)
					)
					(number "8"
						(effects
							(font
								(size 1.27 1.27)
							)
						)
					)
				)
				(pin passive line
					(at 27.94 -12.7 180)
					(length 2.54)
					(hide yes)
					(name "VOUT2"
						(effects
							(font
								(size 1.27 1.27)
							)
						)
					)
					(number "9"
						(effects
							(font
								(size 1.27 1.27)
							)
						)
					)
				)
				(pin power_out line
					(at 27.94 -15.24 180)
					(length 2.54)
					(name "SW2"
						(effects
							(font
								(size 1.27 1.27)
							)
						)
					)
					(number "11"
						(effects
							(font
								(size 1.27 1.27)
							)
						)
					)
				)
				(pin input line
					(at 27.94 -17.78 180)
					(length 2.54)
					(name "FB2"
						(effects
							(font
								(size 1.27 1.27)
							)
						)
					)
					(number "6"
						(effects
							(font
								(size 1.27 1.27)
							)
						)
					)
				)
				(pin power_out line
					(at 27.94 -22.86 180)
					(length 2.54)
					(name "VOUT3"
						(effects
							(font
								(size 1.27 1.27)
							)
						)
					)
					(number "1"
						(effects
							(font
								(size 1.27 1.27)
							)
						)
					)
				)
				(pin passive line
					(at 27.94 -22.86 180)
					(length 2.54)
					(hide yes)
					(name "VOUT3"
						(effects
							(font
								(size 1.27 1.27)
							)
						)
					)
					(number "32"
						(effects
							(font
								(size 1.27 1.27)
							)
						)
					)
				)
				(pin input line
					(at 27.94 -25.4 180)
					(length 2.54)
					(name "FB3"
						(effects
							(font
								(size 1.27 1.27)
							)
						)
					)
					(number "31"
						(effects
							(font
								(size 1.27 1.27)
							)
						)
					)
				)
				(pin power_out line
					(at 27.94 -27.94 180)
					(length 2.54)
					(name "SGND2"
						(effects
							(font
								(size 1.27 1.27)
							)
						)
					)
					(number "30"
						(effects
							(font
								(size 1.27 1.27)
							)
						)
					)
				)
				(pin power_out line
					(at 27.94 -33.02 180)
					(length 2.54)
					(name "VOUT4"
						(effects
							(font
								(size 1.27 1.27)
							)
						)
					)
					(number "22"
						(effects
							(font
								(size 1.27 1.27)
							)
						)
					)
				)
				(pin passive line
					(at 27.94 -33.02 180)
					(length 2.54)
					(hide yes)
					(name "VOUT4"
						(effects
							(font
								(size 1.27 1.27)
							)
						)
					)
					(number "23"
						(effects
							(font
								(size 1.27 1.27)
							)
						)
					)
				)
				(pin input line
					(at 27.94 -35.56 180)
					(length 2.54)
					(name "FB4"
						(effects
							(font
								(size 1.27 1.27)
							)
						)
					)
					(number "24"
						(effects
							(font
								(size 1.27 1.27)
							)
						)
					)
				)
			)
		)
	(symbol "antmicroPMICVoltageRegulatorsLinear:LT3033EUDC_QFN"
			(exclude_from_sim no)
			(in_bom yes)
			(on_board yes)
			(property "Reference" "U"
				(at 35.56 -2.54 0)
				(effects
					(font
						(size 1.27 1.27)
						(thickness 0.15)
					)
					(justify left bottom)
				)
			)
			(property "Value" "LT3033EUDC_QFN"
				(at 35.56 -7.62 0)
				(effects
					(font
						(size 1.27 1.27)
						(thickness 0.15)
					)
					(justify left bottom)
					(hide yes)
				)
			)
			(property "Footprint" "antmicro-footprints:QFN-20-4EP_3x4x0.75mm_P0.5mm_Layout4x6_LT3033"
				(at 35.56 -10.16 0)
				(effects
					(font
						(size 1.27 1.27)
						(thickness 0.15)
					)
					(justify left bottom)
					(hide yes)
				)
			)
			(property "Datasheet" "https://www.analog.com/media/en/technical-documentation/data-sheets/LT3033.pdf"
				(at 35.56 -12.7 0)
				(effects
					(font
						(size 1.27 1.27)
						(thickness 0.15)
					)
					(justify left bottom)
					(hide yes)
				)
			)
			(property "Description" ""
				(at 0 0 0)
				(effects
					(font
						(size 1.27 1.27)
					)
					(hide yes)
				)
			)
			(property "MPN" "LT3033EUDC#PBF"
				(at 35.56 -5.08 0)
				(effects
					(font
						(size 1.27 1.27)
						(thickness 0.15)
					)
					(justify left bottom)
				)
			)
			(property "Manufacturer" "Analog Devices"
				(at 35.56 -15.24 0)
				(effects
					(font
						(size 1.27 1.27)
						(thickness 0.15)
					)
					(justify left bottom)
					(hide yes)
				)
			)
			(property "Author" "Antmicro"
				(at 35.56 -17.78 0)
				(effects
					(font
						(size 1.27 1.27)
						(thickness 0.15)
					)
					(justify left bottom)
					(hide yes)
				)
			)
			(property "License" "Apache-2.0"
				(at 35.56 -20.32 0)
				(effects
					(font
						(size 1.27 1.27)
						(thickness 0.15)
					)
					(justify left bottom)
					(hide yes)
				)
			)
			(symbol "LT3033EUDC_QFN_1_1"
				(rectangle
					(start 2.54 2.54)
					(end 17.78 -20.32)
					(stroke
						(width 0.254)
						(type default)
					)
					(fill
						(type background)
					)
				)
				(pin power_in line
					(at 0 0 0)
					(length 2.54)
					(name "IN"
						(effects
							(font
								(size 1.27 1.27)
							)
						)
					)
					(number "1"
						(effects
							(font
								(size 1.27 1.27)
							)
						)
					)
				)
				(pin passive line
					(at 0 0 0)
					(length 2.54)
					(hide yes)
					(name "IN"
						(effects
							(font
								(size 1.27 1.27)
							)
						)
					)
					(number "15"
						(effects
							(font
								(size 1.27 1.27)
							)
						)
					)
				)
				(pin passive line
					(at 0 0 0)
					(length 2.54)
					(hide yes)
					(name "IN"
						(effects
							(font
								(size 1.27 1.27)
							)
						)
					)
					(number "16"
						(effects
							(font
								(size 1.27 1.27)
							)
						)
					)
				)
				(pin passive line
					(at 0 0 0)
					(length 2.54)
					(hide yes)
					(name "IN"
						(effects
							(font
								(size 1.27 1.27)
							)
						)
					)
					(number "2"
						(effects
							(font
								(size 1.27 1.27)
							)
						)
					)
				)
				(pin passive line
					(at 0 0 0)
					(length 2.54)
					(hide yes)
					(name "IN"
						(effects
							(font
								(size 1.27 1.27)
							)
						)
					)
					(number "21"
						(effects
							(font
								(size 1.27 1.27)
							)
						)
					)
				)
				(pin passive line
					(at 0 0 0)
					(length 2.54)
					(hide yes)
					(name "IN"
						(effects
							(font
								(size 1.27 1.27)
							)
						)
					)
					(number "22"
						(effects
							(font
								(size 1.27 1.27)
							)
						)
					)
				)
				(pin input line
					(at 0 -5.08 0)
					(length 2.54)
					(name "~{SHDN}"
						(effects
							(font
								(size 1.27 1.27)
							)
						)
					)
					(number "12"
						(effects
							(font
								(size 1.27 1.27)
							)
						)
					)
				)
				(pin output line
					(at 0 -7.62 0)
					(length 2.54)
					(name "IMON"
						(effects
							(font
								(size 1.27 1.27)
							)
						)
					)
					(number "8"
						(effects
							(font
								(size 1.27 1.27)
							)
						)
					)
				)
				(pin passive line
					(at 0 -12.7 0)
					(length 2.54)
					(name "ILIM"
						(effects
							(font
								(size 1.27 1.27)
							)
						)
					)
					(number "7"
						(effects
							(font
								(size 1.27 1.27)
							)
						)
					)
				)
				(pin power_in line
					(at 0 -17.78 0)
					(length 2.54)
					(name "GND"
						(effects
							(font
								(size 1.27 1.27)
							)
						)
					)
					(number "5"
						(effects
							(font
								(size 1.27 1.27)
							)
						)
					)
				)
				(pin passive line
					(at 0 -17.78 0)
					(length 2.54)
					(hide yes)
					(name "GND"
						(effects
							(font
								(size 1.27 1.27)
							)
						)
					)
					(number "6"
						(effects
							(font
								(size 1.27 1.27)
							)
						)
					)
				)
				(pin power_out line
					(at 20.32 0 180)
					(length 2.54)
					(name "OUT"
						(effects
							(font
								(size 1.27 1.27)
							)
						)
					)
					(number "13"
						(effects
							(font
								(size 1.27 1.27)
							)
						)
					)
				)
				(pin passive line
					(at 20.32 0 180)
					(length 2.54)
					(hide yes)
					(name "OUT"
						(effects
							(font
								(size 1.27 1.27)
							)
						)
					)
					(number "14"
						(effects
							(font
								(size 1.27 1.27)
							)
						)
					)
				)
				(pin passive line
					(at 20.32 0 180)
					(length 2.54)
					(hide yes)
					(name "OUT"
						(effects
							(font
								(size 1.27 1.27)
							)
						)
					)
					(number "17"
						(effects
							(font
								(size 1.27 1.27)
							)
						)
					)
				)
				(pin passive line
					(at 20.32 0 180)
					(length 2.54)
					(hide yes)
					(name "OUT"
						(effects
							(font
								(size 1.27 1.27)
							)
						)
					)
					(number "18"
						(effects
							(font
								(size 1.27 1.27)
							)
						)
					)
				)
				(pin passive line
					(at 20.32 0 180)
					(length 2.54)
					(hide yes)
					(name "OUT"
						(effects
							(font
								(size 1.27 1.27)
							)
						)
					)
					(number "19"
						(effects
							(font
								(size 1.27 1.27)
							)
						)
					)
				)
				(pin passive line
					(at 20.32 0 180)
					(length 2.54)
					(hide yes)
					(name "OUT"
						(effects
							(font
								(size 1.27 1.27)
							)
						)
					)
					(number "20"
						(effects
							(font
								(size 1.27 1.27)
							)
						)
					)
				)
				(pin passive line
					(at 20.32 0 180)
					(length 2.54)
					(hide yes)
					(name "OUT"
						(effects
							(font
								(size 1.27 1.27)
							)
						)
					)
					(number "23"
						(effects
							(font
								(size 1.27 1.27)
							)
						)
					)
				)
				(pin passive line
					(at 20.32 0 180)
					(length 2.54)
					(hide yes)
					(name "OUT"
						(effects
							(font
								(size 1.27 1.27)
							)
						)
					)
					(number "24"
						(effects
							(font
								(size 1.27 1.27)
							)
						)
					)
				)
				(pin passive line
					(at 20.32 0 180)
					(length 2.54)
					(hide yes)
					(name "OUT"
						(effects
							(font
								(size 1.27 1.27)
							)
						)
					)
					(number "3"
						(effects
							(font
								(size 1.27 1.27)
							)
						)
					)
				)
				(pin passive line
					(at 20.32 0 180)
					(length 2.54)
					(hide yes)
					(name "OUT"
						(effects
							(font
								(size 1.27 1.27)
							)
						)
					)
					(number "4"
						(effects
							(font
								(size 1.27 1.27)
							)
						)
					)
				)
				(pin input line
					(at 20.32 -7.62 180)
					(length 2.54)
					(name "ADJ"
						(effects
							(font
								(size 1.27 1.27)
							)
						)
					)
					(number "10"
						(effects
							(font
								(size 1.27 1.27)
							)
						)
					)
				)
				(pin open_collector line
					(at 20.32 -15.24 180)
					(length 2.54)
					(name "PWRGD"
						(effects
							(font
								(size 1.27 1.27)
							)
						)
					)
					(number "11"
						(effects
							(font
								(size 1.27 1.27)
							)
						)
					)
				)
				(pin passive line
					(at 20.32 -17.78 180)
					(length 2.54)
					(name "REF/BYP"
						(effects
							(font
								(size 1.27 1.27)
							)
						)
					)
					(number "9"
						(effects
							(font
								(size 1.27 1.27)
							)
						)
					)
				)
			)
		)
	(symbol "antmicroResistorNetworksArrays:R_4x100R_0402_array"
			(pin_names
				(hide yes)
			)
			(exclude_from_sim no)
			(in_bom yes)
			(on_board yes)
			(property "Reference" "R"
				(at 26.67 -2.54 0)
				(effects
					(font
						(size 1.27 1.27)
						(thickness 0.15)
					)
					(justify left bottom)
				)
			)
			(property "Value" "R_4x100R_0402_array"
				(at 26.67 -5.08 0)
				(effects
					(font
						(size 1.27 1.27)
						(thickness 0.15)
					)
					(justify left bottom)
					(hide yes)
				)
			)
			(property "Footprint" "antmicro-footprints:R_Array_4x0402_Panasonic_EXB28V"
				(at 26.67 -10.16 0)
				(effects
					(font
						(size 1.27 1.27)
						(thickness 0.15)
					)
					(justify left bottom)
					(hide yes)
				)
			)
			(property "Datasheet" "http://industrial.panasonic.com/cdbs/www-data/pdf/AOC0000/AOC0000C14.pdf"
				(at 26.67 -12.7 0)
				(effects
					(font
						(size 1.27 1.27)
						(thickness 0.15)
					)
					(justify left bottom)
					(hide yes)
				)
			)
			(property "Description" "Fixed Network Resistor, 100 ohm, Isolated, 4 Resistors, 0804 [2010 Metric], Convex, ± 5%"
				(at 0 0 0)
				(effects
					(font
						(size 1.27 1.27)
					)
					(hide yes)
				)
			)
			(property "MPN" "EXB-28V101JX"
				(at 26.67 -15.24 0)
				(effects
					(font
						(size 1.27 1.27)
						(thickness 0.15)
					)
					(justify left bottom)
					(hide yes)
				)
			)
			(property "Manufacturer" "Panasonic"
				(at 26.67 -17.78 0)
				(effects
					(font
						(size 1.27 1.27)
						(thickness 0.15)
					)
					(justify left bottom)
					(hide yes)
				)
			)
			(property "Author" "Antmicro"
				(at 26.67 -20.32 0)
				(effects
					(font
						(size 1.27 1.27)
						(thickness 0.15)
					)
					(justify left bottom)
					(hide yes)
				)
			)
			(property "License" "Apache-2.0"
				(at 26.67 -22.86 0)
				(effects
					(font
						(size 1.27 1.27)
						(thickness 0.15)
					)
					(justify left bottom)
					(hide yes)
				)
			)
			(property "Val" "R_4x100R_0402"
				(at 26.67 -7.62 0)
				(effects
					(font
						(size 1.27 1.27)
					)
					(justify left bottom)
				)
			)
			(property "ki_keywords" "0402, SMT, RESISTOR, PASSIVE"
				(at 0 0 0)
				(effects
					(font
						(size 1.27 1.27)
					)
					(hide yes)
				)
			)
			(symbol "R_4x100R_0402_array_0_1"
				(polyline
					(pts
						(xy 2.54 0) (xy 3.175 0)
					)
					(stroke
						(width 0)
						(type default)
					)
					(fill
						(type none)
					)
				)
				(polyline
					(pts
						(xy 2.54 -2.54) (xy 3.175 -2.54)
					)
					(stroke
						(width 0)
						(type default)
					)
					(fill
						(type none)
					)
				)
				(polyline
					(pts
						(xy 2.54 -5.08) (xy 3.175 -5.08)
					)
					(stroke
						(width 0)
						(type default)
					)
					(fill
						(type none)
					)
				)
				(polyline
					(pts
						(xy 2.54 -7.62) (xy 3.175 -7.62)
					)
					(stroke
						(width 0)
						(type default)
					)
					(fill
						(type none)
					)
				)
				(rectangle
					(start 2.667 1.27)
					(end 7.493 -8.89)
					(stroke
						(width 0.254)
						(type default)
					)
					(fill
						(type background)
					)
				)
				(rectangle
					(start 6.985 0.635)
					(end 3.175 -0.635)
					(stroke
						(width 0.254)
						(type default)
					)
					(fill
						(type none)
					)
				)
				(polyline
					(pts
						(xy 6.985 0) (xy 7.62 0)
					)
					(stroke
						(width 0)
						(type default)
					)
					(fill
						(type none)
					)
				)
				(rectangle
					(start 6.985 -1.905)
					(end 3.175 -3.175)
					(stroke
						(width 0.254)
						(type default)
					)
					(fill
						(type none)
					)
				)
				(polyline
					(pts
						(xy 6.985 -2.54) (xy 7.62 -2.54)
					)
					(stroke
						(width 0)
						(type default)
					)
					(fill
						(type none)
					)
				)
				(rectangle
					(start 6.985 -4.445)
					(end 3.175 -5.715)
					(stroke
						(width 0.254)
						(type default)
					)
					(fill
						(type none)
					)
				)
				(polyline
					(pts
						(xy 6.985 -5.08) (xy 7.62 -5.08)
					)
					(stroke
						(width 0)
						(type default)
					)
					(fill
						(type none)
					)
				)
				(rectangle
					(start 6.985 -6.985)
					(end 3.175 -8.255)
					(stroke
						(width 0.254)
						(type default)
					)
					(fill
						(type none)
					)
				)
				(polyline
					(pts
						(xy 6.985 -7.62) (xy 7.62 -7.62)
					)
					(stroke
						(width 0)
						(type default)
					)
					(fill
						(type none)
					)
				)
			)
			(symbol "R_4x100R_0402_array_1_1"
				(pin passive line
					(at 0 0 0)
					(length 2.54)
					(name "R1.1"
						(effects
							(font
								(size 1.27 1.27)
							)
						)
					)
					(number "1"
						(effects
							(font
								(size 1.27 1.27)
							)
						)
					)
				)
				(pin passive line
					(at 0 -2.54 0)
					(length 2.54)
					(name "R2.1"
						(effects
							(font
								(size 1.27 1.27)
							)
						)
					)
					(number "2"
						(effects
							(font
								(size 1.27 1.27)
							)
						)
					)
				)
				(pin passive line
					(at 0 -5.08 0)
					(length 2.54)
					(name "R3.1"
						(effects
							(font
								(size 1.27 1.27)
							)
						)
					)
					(number "3"
						(effects
							(font
								(size 1.27 1.27)
							)
						)
					)
				)
				(pin passive line
					(at 0 -7.62 0)
					(length 2.54)
					(name "R4.1"
						(effects
							(font
								(size 1.27 1.27)
							)
						)
					)
					(number "4"
						(effects
							(font
								(size 1.27 1.27)
							)
						)
					)
				)
				(pin passive line
					(at 10.16 0 180)
					(length 2.54)
					(name "R1.2"
						(effects
							(font
								(size 1.27 1.27)
							)
						)
					)
					(number "8"
						(effects
							(font
								(size 1.27 1.27)
							)
						)
					)
				)
				(pin passive line
					(at 10.16 -2.54 180)
					(length 2.54)
					(name "R2.2"
						(effects
							(font
								(size 1.27 1.27)
							)
						)
					)
					(number "7"
						(effects
							(font
								(size 1.27 1.27)
							)
						)
					)
				)
				(pin passive line
					(at 10.16 -5.08 180)
					(length 2.54)
					(name "R3.2"
						(effects
							(font
								(size 1.27 1.27)
							)
						)
					)
					(number "6"
						(effects
							(font
								(size 1.27 1.27)
							)
						)
					)
				)
				(pin passive line
					(at 10.16 -7.62 180)
					(length 2.54)
					(name "R4.2"
						(effects
							(font
								(size 1.27 1.27)
							)
						)
					)
					(number "5"
						(effects
							(font
								(size 1.27 1.27)
							)
						)
					)
				)
			)
		)
	(symbol "antmicroResistors0402:R_0R_0402"
			(pin_numbers
				(hide yes)
			)
			(pin_names
				(hide yes)
			)
			(exclude_from_sim no)
			(in_bom yes)
			(on_board yes)
			(property "Reference" "R"
				(at 20.32 -5.08 0)
				(effects
					(font
						(size 1.27 1.27)
						(thickness 0.15)
					)
					(justify left bottom)
				)
			)
			(property "Value" "R_0R_0402"
				(at 20.32 -12.7 0)
				(effects
					(font
						(size 1.27 1.27)
						(thickness 0.15)
					)
					(justify left bottom)
					(hide yes)
				)
			)
			(property "Footprint" "antmicro-footprints:R_0402_1005Metric"
				(at 20.32 -15.24 0)
				(effects
					(font
						(size 1.27 1.27)
						(thickness 0.15)
					)
					(justify left bottom)
					(hide yes)
				)
			)
			(property "Datasheet" "https://industrial.panasonic.com/cdbs/www-data/pdf/RDA0000/AOA0000C301.pdf"
				(at 20.32 -17.78 0)
				(effects
					(font
						(size 1.27 1.27)
						(thickness 0.15)
					)
					(justify left bottom)
					(hide yes)
				)
			)
			(property "Description" "SMD Chip Resistor, Jumper, 0 ohm, 100 mW, 0402 [1005 Metric], Thick Film, General Purpose"
				(at 0 0 0)
				(effects
					(font
						(size 1.27 1.27)
					)
					(hide yes)
				)
			)
			(property "MPN" "ERJ2GE0R00X"
				(at 20.32 -20.32 0)
				(effects
					(font
						(size 1.27 1.27)
						(thickness 0.15)
					)
					(justify left bottom)
					(hide yes)
				)
			)
			(property "Manufacturer" "Panasonic"
				(at 20.32 -22.86 0)
				(effects
					(font
						(size 1.27 1.27)
						(thickness 0.15)
					)
					(justify left bottom)
					(hide yes)
				)
			)
			(property "License" "Apache-2.0"
				(at 20.32 -25.4 0)
				(effects
					(font
						(size 1.27 1.27)
						(thickness 0.15)
					)
					(justify left bottom)
					(hide yes)
				)
			)
			(property "Author" "Antmicro"
				(at 20.32 -27.94 0)
				(effects
					(font
						(size 1.27 1.27)
						(thickness 0.15)
					)
					(justify left bottom)
					(hide yes)
				)
			)
			(property "Val" "0R"
				(at 20.32 -7.62 0)
				(effects
					(font
						(size 1.27 1.27)
						(thickness 0.15)
					)
					(justify left bottom)
				)
			)
			(property "Tolerance" "~"
				(at 20.32 -10.16 0)
				(effects
					(font
						(size 1.27 1.27)
					)
					(justify left bottom)
					(hide yes)
				)
			)
			(property "Current" "1A"
				(at 20.32 -30.48 0)
				(effects
					(font
						(size 1.27 1.27)
						(thickness 0.15)
					)
					(justify left bottom)
					(hide yes)
				)
			)
			(property "ki_keywords" "0402, SMT, RESISTOR, PASSIVE"
				(at 0 0 0)
				(effects
					(font
						(size 1.27 1.27)
					)
					(hide yes)
				)
			)
			(symbol "R_0R_0402_0_1"
				(rectangle
					(start 0.635 0.889)
					(end 4.445 -0.889)
					(stroke
						(width 0.254)
						(type default)
					)
					(fill
						(type none)
					)
				)
			)
			(symbol "R_0R_0402_1_1"
				(pin passive line
					(at 0 0 0)
					(length 0.635)
					(name "~"
						(effects
							(font
								(size 1.27 1.27)
							)
						)
					)
					(number "1"
						(effects
							(font
								(size 1.27 1.27)
							)
						)
					)
				)
				(pin passive line
					(at 5.08 0 180)
					(length 0.635)
					(name "~"
						(effects
							(font
								(size 1.27 1.27)
							)
						)
					)
					(number "2"
						(effects
							(font
								(size 1.27 1.27)
							)
						)
					)
				)
			)
		)
	(symbol "antmicroResistors0402:R_100R_0402"
			(pin_numbers
				(hide yes)
			)
			(pin_names
				(hide yes)
			)
			(exclude_from_sim no)
			(in_bom yes)
			(on_board yes)
			(property "Reference" "R"
				(at 20.32 -5.08 0)
				(effects
					(font
						(size 1.27 1.27)
						(thickness 0.15)
					)
					(justify left bottom)
				)
			)
			(property "Value" "R_100R_0402"
				(at 20.32 -12.7 0)
				(effects
					(font
						(size 1.27 1.27)
						(thickness 0.15)
					)
					(justify left bottom)
					(hide yes)
				)
			)
			(property "Footprint" "antmicro-footprints:R_0402_1005Metric"
				(at 20.32 -15.24 0)
				(effects
					(font
						(size 1.27 1.27)
						(thickness 0.15)
					)
					(justify left bottom)
					(hide yes)
				)
			)
			(property "Datasheet" "https://www.bourns.com/docs/product-datasheets/cr.pdf"
				(at 20.32 -17.78 0)
				(effects
					(font
						(size 1.27 1.27)
						(thickness 0.15)
					)
					(justify left bottom)
					(hide yes)
				)
			)
			(property "Description" "SMD Chip Resistor, 100 ohm, ± 1%, 62.5 mW, 0402 [1005 Metric], Thick Film, General Purpose"
				(at 0 0 0)
				(effects
					(font
						(size 1.27 1.27)
					)
					(hide yes)
				)
			)
			(property "MPN" "CR0402-FX-1000GLF"
				(at 20.32 -20.32 0)
				(effects
					(font
						(size 1.27 1.27)
						(thickness 0.15)
					)
					(justify left bottom)
					(hide yes)
				)
			)
			(property "Manufacturer" "Bourns"
				(at 20.32 -22.86 0)
				(effects
					(font
						(size 1.27 1.27)
						(thickness 0.15)
					)
					(justify left bottom)
					(hide yes)
				)
			)
			(property "License" "Apache-2.0"
				(at 20.32 -25.4 0)
				(effects
					(font
						(size 1.27 1.27)
						(thickness 0.15)
					)
					(justify left bottom)
					(hide yes)
				)
			)
			(property "Author" "Antmicro"
				(at 20.32 -27.94 0)
				(effects
					(font
						(size 1.27 1.27)
						(thickness 0.15)
					)
					(justify left bottom)
					(hide yes)
				)
			)
			(property "Val" "100R"
				(at 20.32 -7.62 0)
				(effects
					(font
						(size 1.27 1.27)
						(thickness 0.15)
					)
					(justify left bottom)
				)
			)
			(property "Tolerance" "1%"
				(at 20.32 -10.16 0)
				(effects
					(font
						(size 1.27 1.27)
					)
					(justify left bottom)
					(hide yes)
				)
			)
			(property "ki_keywords" "0402, SMT, RESISTOR, PASSIVE"
				(at 0 0 0)
				(effects
					(font
						(size 1.27 1.27)
					)
					(hide yes)
				)
			)
			(symbol "R_100R_0402_0_1"
				(rectangle
					(start 0.635 0.889)
					(end 4.445 -0.889)
					(stroke
						(width 0.254)
						(type default)
					)
					(fill
						(type none)
					)
				)
			)
			(symbol "R_100R_0402_1_1"
				(pin passive line
					(at 0 0 0)
					(length 0.635)
					(name "~"
						(effects
							(font
								(size 1.27 1.27)
							)
						)
					)
					(number "1"
						(effects
							(font
								(size 1.27 1.27)
							)
						)
					)
				)
				(pin passive line
					(at 5.08 0 180)
					(length 0.635)
					(name "~"
						(effects
							(font
								(size 1.27 1.27)
							)
						)
					)
					(number "2"
						(effects
							(font
								(size 1.27 1.27)
							)
						)
					)
				)
			)
		)
	(symbol "antmicroResistors0402:R_100k_0402"
			(pin_numbers
				(hide yes)
			)
			(pin_names
				(hide yes)
			)
			(exclude_from_sim no)
			(in_bom yes)
			(on_board yes)
			(property "Reference" "R"
				(at 20.32 -5.08 0)
				(effects
					(font
						(size 1.27 1.27)
						(thickness 0.15)
					)
					(justify left bottom)
				)
			)
			(property "Value" "R_100k_0402"
				(at 20.32 -12.7 0)
				(effects
					(font
						(size 1.27 1.27)
						(thickness 0.15)
					)
					(justify left bottom)
					(hide yes)
				)
			)
			(property "Footprint" "antmicro-footprints:R_0402_1005Metric"
				(at 20.32 -15.24 0)
				(effects
					(font
						(size 1.27 1.27)
						(thickness 0.15)
					)
					(justify left bottom)
					(hide yes)
				)
			)
			(property "Datasheet" "https://www.bourns.com/docs/product-datasheets/cr.pdf"
				(at 20.32 -17.78 0)
				(effects
					(font
						(size 1.27 1.27)
						(thickness 0.15)
					)
					(justify left bottom)
					(hide yes)
				)
			)
			(property "Description" "SMD Chip Resistor, 100 kohm, ± 1%, 62.5 mW, 0402 [1005 Metric], Thick Film, General Purpose"
				(at 0 0 0)
				(effects
					(font
						(size 1.27 1.27)
					)
					(hide yes)
				)
			)
			(property "MPN" "CR0402-FX-1003GLF"
				(at 20.32 -20.32 0)
				(effects
					(font
						(size 1.27 1.27)
						(thickness 0.15)
					)
					(justify left bottom)
					(hide yes)
				)
			)
			(property "Manufacturer" "Bourns"
				(at 20.32 -22.86 0)
				(effects
					(font
						(size 1.27 1.27)
						(thickness 0.15)
					)
					(justify left bottom)
					(hide yes)
				)
			)
			(property "License" "Apache-2.0"
				(at 20.32 -25.4 0)
				(effects
					(font
						(size 1.27 1.27)
						(thickness 0.15)
					)
					(justify left bottom)
					(hide yes)
				)
			)
			(property "Author" "Antmicro"
				(at 20.32 -27.94 0)
				(effects
					(font
						(size 1.27 1.27)
						(thickness 0.15)
					)
					(justify left bottom)
					(hide yes)
				)
			)
			(property "Val" "100k"
				(at 20.32 -7.62 0)
				(effects
					(font
						(size 1.27 1.27)
						(thickness 0.15)
					)
					(justify left bottom)
				)
			)
			(property "Tolerance" "1%"
				(at 20.32 -10.16 0)
				(effects
					(font
						(size 1.27 1.27)
					)
					(justify left bottom)
					(hide yes)
				)
			)
			(property "ki_keywords" "0402, SMT, RESISTOR, PASSIVE"
				(at 0 0 0)
				(effects
					(font
						(size 1.27 1.27)
					)
					(hide yes)
				)
			)
			(symbol "R_100k_0402_0_1"
				(rectangle
					(start 0.635 0.889)
					(end 4.445 -0.889)
					(stroke
						(width 0.254)
						(type default)
					)
					(fill
						(type none)
					)
				)
			)
			(symbol "R_100k_0402_1_1"
				(pin passive line
					(at 0 0 0)
					(length 0.635)
					(name "~"
						(effects
							(font
								(size 1.27 1.27)
							)
						)
					)
					(number "1"
						(effects
							(font
								(size 1.27 1.27)
							)
						)
					)
				)
				(pin passive line
					(at 5.08 0 180)
					(length 0.635)
					(name "~"
						(effects
							(font
								(size 1.27 1.27)
							)
						)
					)
					(number "2"
						(effects
							(font
								(size 1.27 1.27)
							)
						)
					)
				)
			)
		)
	(symbol "antmicroResistors0402:R_120k_0402"
			(pin_numbers
				(hide yes)
			)
			(pin_names
				(hide yes)
			)
			(exclude_from_sim no)
			(in_bom yes)
			(on_board yes)
			(property "Reference" "R"
				(at 20.32 -5.08 0)
				(effects
					(font
						(size 1.27 1.27)
						(thickness 0.15)
					)
					(justify left bottom)
				)
			)
			(property "Value" "R_120k_0402"
				(at 20.32 -12.7 0)
				(effects
					(font
						(size 1.27 1.27)
						(thickness 0.15)
					)
					(justify left bottom)
					(hide yes)
				)
			)
			(property "Footprint" "antmicro-footprints:R_0402_1005Metric"
				(at 20.32 -15.24 0)
				(effects
					(font
						(size 1.27 1.27)
						(thickness 0.15)
					)
					(justify left bottom)
					(hide yes)
				)
			)
			(property "Datasheet" "https://www.bourns.com/docs/product-datasheets/cr.pdf"
				(at 20.32 -17.78 0)
				(effects
					(font
						(size 1.27 1.27)
						(thickness 0.15)
					)
					(justify left bottom)
					(hide yes)
				)
			)
			(property "Description" "SMD Chip Resistor, 120 kohm, ± 1%, 100 mW, 0402 [1005 Metric], Thick Film, Precision"
				(at 0 0 0)
				(effects
					(font
						(size 1.27 1.27)
					)
					(hide yes)
				)
			)
			(property "MPN" "CR0402-FX-1203GLF"
				(at 20.32 -20.32 0)
				(effects
					(font
						(size 1.27 1.27)
						(thickness 0.15)
					)
					(justify left bottom)
					(hide yes)
				)
			)
			(property "Manufacturer" "Bourns"
				(at 20.32 -22.86 0)
				(effects
					(font
						(size 1.27 1.27)
						(thickness 0.15)
					)
					(justify left bottom)
					(hide yes)
				)
			)
			(property "License" "Apache-2.0"
				(at 20.32 -25.4 0)
				(effects
					(font
						(size 1.27 1.27)
						(thickness 0.15)
					)
					(justify left bottom)
					(hide yes)
				)
			)
			(property "Author" "Antmicro"
				(at 20.32 -27.94 0)
				(effects
					(font
						(size 1.27 1.27)
						(thickness 0.15)
					)
					(justify left bottom)
					(hide yes)
				)
			)
			(property "Val" "120k"
				(at 20.32 -7.62 0)
				(effects
					(font
						(size 1.27 1.27)
						(thickness 0.15)
					)
					(justify left bottom)
				)
			)
			(property "Tolerance" "1%"
				(at 20.32 -10.16 0)
				(effects
					(font
						(size 1.27 1.27)
					)
					(justify left bottom)
					(hide yes)
				)
			)
			(property "ki_keywords" "0402, SMT, RESISTOR, PASSIVE"
				(at 0 0 0)
				(effects
					(font
						(size 1.27 1.27)
					)
					(hide yes)
				)
			)
			(symbol "R_120k_0402_0_1"
				(rectangle
					(start 0.635 0.889)
					(end 4.445 -0.889)
					(stroke
						(width 0.254)
						(type default)
					)
					(fill
						(type none)
					)
				)
			)
			(symbol "R_120k_0402_1_1"
				(pin passive line
					(at 0 0 0)
					(length 0.635)
					(name "~"
						(effects
							(font
								(size 1.27 1.27)
							)
						)
					)
					(number "1"
						(effects
							(font
								(size 1.27 1.27)
							)
						)
					)
				)
				(pin passive line
					(at 5.08 0 180)
					(length 0.635)
					(name "~"
						(effects
							(font
								(size 1.27 1.27)
							)
						)
					)
					(number "2"
						(effects
							(font
								(size 1.27 1.27)
							)
						)
					)
				)
			)
		)
	(symbol "antmicroResistors0402:R_130k_0402"
			(pin_numbers
				(hide yes)
			)
			(pin_names
				(hide yes)
			)
			(exclude_from_sim no)
			(in_bom yes)
			(on_board yes)
			(property "Reference" "R"
				(at 20.32 -5.08 0)
				(effects
					(font
						(size 1.27 1.27)
						(thickness 0.15)
					)
					(justify left bottom)
				)
			)
			(property "Value" "R_130k_0402"
				(at 20.32 -12.7 0)
				(effects
					(font
						(size 1.27 1.27)
						(thickness 0.15)
					)
					(justify left bottom)
					(hide yes)
				)
			)
			(property "Footprint" "antmicro-footprints:R_0402_1005Metric"
				(at 20.32 -15.24 0)
				(effects
					(font
						(size 1.27 1.27)
						(thickness 0.15)
					)
					(justify left bottom)
					(hide yes)
				)
			)
			(property "Datasheet" "https://www.bourns.com/docs/product-datasheets/cr.pdf"
				(at 20.32 -17.78 0)
				(effects
					(font
						(size 1.27 1.27)
						(thickness 0.15)
					)
					(justify left bottom)
					(hide yes)
				)
			)
			(property "Description" "SMD Chip Resistor, 130 kohm, ± 1%, 62.5 mW, 0402 [1005 Metric], Thick Film, General Purpose"
				(at 0 0 0)
				(effects
					(font
						(size 1.27 1.27)
					)
					(hide yes)
				)
			)
			(property "MPN" "CR0402-FX-1303GLF"
				(at 20.32 -20.32 0)
				(effects
					(font
						(size 1.27 1.27)
						(thickness 0.15)
					)
					(justify left bottom)
					(hide yes)
				)
			)
			(property "Manufacturer" "Bourns"
				(at 20.32 -22.86 0)
				(effects
					(font
						(size 1.27 1.27)
						(thickness 0.15)
					)
					(justify left bottom)
					(hide yes)
				)
			)
			(property "License" "Apache-2.0"
				(at 20.32 -25.4 0)
				(effects
					(font
						(size 1.27 1.27)
						(thickness 0.15)
					)
					(justify left bottom)
					(hide yes)
				)
			)
			(property "Author" "Antmicro"
				(at 20.32 -27.94 0)
				(effects
					(font
						(size 1.27 1.27)
						(thickness 0.15)
					)
					(justify left bottom)
					(hide yes)
				)
			)
			(property "Val" "130k"
				(at 20.32 -7.62 0)
				(effects
					(font
						(size 1.27 1.27)
						(thickness 0.15)
					)
					(justify left bottom)
				)
			)
			(property "Tolerance" "1%"
				(at 20.32 -10.16 0)
				(effects
					(font
						(size 1.27 1.27)
					)
					(justify left bottom)
					(hide yes)
				)
			)
			(property "ki_keywords" "0402, SMT, RESISTOR, PASSIVE"
				(at 0 0 0)
				(effects
					(font
						(size 1.27 1.27)
					)
					(hide yes)
				)
			)
			(symbol "R_130k_0402_0_1"
				(rectangle
					(start 0.635 0.889)
					(end 4.445 -0.889)
					(stroke
						(width 0.254)
						(type default)
					)
					(fill
						(type none)
					)
				)
			)
			(symbol "R_130k_0402_1_1"
				(pin passive line
					(at 0 0 0)
					(length 0.635)
					(name "~"
						(effects
							(font
								(size 1.27 1.27)
							)
						)
					)
					(number "1"
						(effects
							(font
								(size 1.27 1.27)
							)
						)
					)
				)
				(pin passive line
					(at 5.08 0 180)
					(length 0.635)
					(name "~"
						(effects
							(font
								(size 1.27 1.27)
							)
						)
					)
					(number "2"
						(effects
							(font
								(size 1.27 1.27)
							)
						)
					)
				)
			)
		)
	(symbol "antmicroResistors0402:R_1k_0402"
			(pin_numbers
				(hide yes)
			)
			(pin_names
				(hide yes)
			)
			(exclude_from_sim no)
			(in_bom yes)
			(on_board yes)
			(property "Reference" "R"
				(at 20.32 -5.08 0)
				(effects
					(font
						(size 1.27 1.27)
						(thickness 0.15)
					)
					(justify left bottom)
				)
			)
			(property "Value" "R_1k_0402"
				(at 20.32 -12.7 0)
				(effects
					(font
						(size 1.27 1.27)
						(thickness 0.15)
					)
					(justify left bottom)
					(hide yes)
				)
			)
			(property "Footprint" "antmicro-footprints:R_0402_1005Metric"
				(at 20.32 -15.24 0)
				(effects
					(font
						(size 1.27 1.27)
						(thickness 0.15)
					)
					(justify left bottom)
					(hide yes)
				)
			)
			(property "Datasheet" "https://www.bourns.com/docs/product-datasheets/cr.pdf"
				(at 20.32 -17.78 0)
				(effects
					(font
						(size 1.27 1.27)
						(thickness 0.15)
					)
					(justify left bottom)
					(hide yes)
				)
			)
			(property "Description" "SMD Chip Resistor, 1 kohm, ± 1%, 63 mW, 0402 [1005 Metric], Thick Film, General Purpose"
				(at 0 0 0)
				(effects
					(font
						(size 1.27 1.27)
					)
					(hide yes)
				)
			)
			(property "MPN" "CR0402-FX-1001GLF"
				(at 20.32 -20.32 0)
				(effects
					(font
						(size 1.27 1.27)
						(thickness 0.15)
					)
					(justify left bottom)
					(hide yes)
				)
			)
			(property "Manufacturer" "Bourns"
				(at 20.32 -22.86 0)
				(effects
					(font
						(size 1.27 1.27)
						(thickness 0.15)
					)
					(justify left bottom)
					(hide yes)
				)
			)
			(property "License" "Apache-2.0"
				(at 20.32 -25.4 0)
				(effects
					(font
						(size 1.27 1.27)
						(thickness 0.15)
					)
					(justify left bottom)
					(hide yes)
				)
			)
			(property "Author" "Antmicro"
				(at 20.32 -27.94 0)
				(effects
					(font
						(size 1.27 1.27)
						(thickness 0.15)
					)
					(justify left bottom)
					(hide yes)
				)
			)
			(property "Val" "1k"
				(at 20.32 -7.62 0)
				(effects
					(font
						(size 1.27 1.27)
						(thickness 0.15)
					)
					(justify left bottom)
				)
			)
			(property "Tolerance" "1%"
				(at 20.32 -10.16 0)
				(effects
					(font
						(size 1.27 1.27)
					)
					(justify left bottom)
					(hide yes)
				)
			)
			(property "ki_keywords" "0402, SMT, RESISTOR, PASSIVE"
				(at 0 0 0)
				(effects
					(font
						(size 1.27 1.27)
					)
					(hide yes)
				)
			)
			(symbol "R_1k_0402_0_1"
				(rectangle
					(start 0.635 0.889)
					(end 4.445 -0.889)
					(stroke
						(width 0.254)
						(type default)
					)
					(fill
						(type none)
					)
				)
			)
			(symbol "R_1k_0402_1_1"
				(pin passive line
					(at 0 0 0)
					(length 0.635)
					(name "~"
						(effects
							(font
								(size 1.27 1.27)
							)
						)
					)
					(number "1"
						(effects
							(font
								(size 1.27 1.27)
							)
						)
					)
				)
				(pin passive line
					(at 5.08 0 180)
					(length 0.635)
					(name "~"
						(effects
							(font
								(size 1.27 1.27)
							)
						)
					)
					(number "2"
						(effects
							(font
								(size 1.27 1.27)
							)
						)
					)
				)
			)
		)
	(symbol "antmicroResistors0402:R_200k_0402"
			(pin_numbers
				(hide yes)
			)
			(pin_names
				(hide yes)
			)
			(exclude_from_sim no)
			(in_bom yes)
			(on_board yes)
			(property "Reference" "R"
				(at 20.32 -5.08 0)
				(effects
					(font
						(size 1.27 1.27)
						(thickness 0.15)
					)
					(justify left bottom)
				)
			)
			(property "Value" "R_200k_0402"
				(at 20.32 -12.7 0)
				(effects
					(font
						(size 1.27 1.27)
						(thickness 0.15)
					)
					(justify left bottom)
					(hide yes)
				)
			)
			(property "Footprint" "antmicro-footprints:R_0402_1005Metric"
				(at 20.32 -15.24 0)
				(effects
					(font
						(size 1.27 1.27)
						(thickness 0.15)
					)
					(justify left bottom)
					(hide yes)
				)
			)
			(property "Datasheet" "https://www.bourns.com/docs/product-datasheets/cr.pdf"
				(at 20.32 -17.78 0)
				(effects
					(font
						(size 1.27 1.27)
						(thickness 0.15)
					)
					(justify left bottom)
					(hide yes)
				)
			)
			(property "Description" "SMD Chip Resistor, 200 kohm, ± 1%, 62.5 mW, 0402 [1005 Metric], Thick Film, General Purpose"
				(at 0 0 0)
				(effects
					(font
						(size 1.27 1.27)
					)
					(hide yes)
				)
			)
			(property "MPN" "CR0402-FX-2003GLF"
				(at 20.32 -20.32 0)
				(effects
					(font
						(size 1.27 1.27)
						(thickness 0.15)
					)
					(justify left bottom)
					(hide yes)
				)
			)
			(property "Manufacturer" "Bourns"
				(at 20.32 -22.86 0)
				(effects
					(font
						(size 1.27 1.27)
						(thickness 0.15)
					)
					(justify left bottom)
					(hide yes)
				)
			)
			(property "License" "Apache-2.0"
				(at 20.32 -25.4 0)
				(effects
					(font
						(size 1.27 1.27)
						(thickness 0.15)
					)
					(justify left bottom)
					(hide yes)
				)
			)
			(property "Author" "Antmicro"
				(at 20.32 -27.94 0)
				(effects
					(font
						(size 1.27 1.27)
						(thickness 0.15)
					)
					(justify left bottom)
					(hide yes)
				)
			)
			(property "Val" "200k"
				(at 20.32 -7.62 0)
				(effects
					(font
						(size 1.27 1.27)
						(thickness 0.15)
					)
					(justify left bottom)
				)
			)
			(property "Tolerance" "1%"
				(at 20.32 -10.16 0)
				(effects
					(font
						(size 1.27 1.27)
					)
					(justify left bottom)
					(hide yes)
				)
			)
			(property "ki_keywords" "0402, SMT, RESISTOR, PASSIVE"
				(at 0 0 0)
				(effects
					(font
						(size 1.27 1.27)
					)
					(hide yes)
				)
			)
			(symbol "R_200k_0402_0_1"
				(rectangle
					(start 0.635 0.889)
					(end 4.445 -0.889)
					(stroke
						(width 0.254)
						(type default)
					)
					(fill
						(type none)
					)
				)
			)
			(symbol "R_200k_0402_1_1"
				(pin passive line
					(at 0 0 0)
					(length 0.635)
					(name "~"
						(effects
							(font
								(size 1.27 1.27)
							)
						)
					)
					(number "1"
						(effects
							(font
								(size 1.27 1.27)
							)
						)
					)
				)
				(pin passive line
					(at 5.08 0 180)
					(length 0.635)
					(name "~"
						(effects
							(font
								(size 1.27 1.27)
							)
						)
					)
					(number "2"
						(effects
							(font
								(size 1.27 1.27)
							)
						)
					)
				)
			)
		)
	(symbol "antmicroResistors0402:R_240R_0402"
			(pin_numbers
				(hide yes)
			)
			(pin_names
				(hide yes)
			)
			(exclude_from_sim no)
			(in_bom yes)
			(on_board yes)
			(property "Reference" "R"
				(at 20.32 -5.08 0)
				(effects
					(font
						(size 1.27 1.27)
						(thickness 0.15)
					)
					(justify left bottom)
				)
			)
			(property "Value" "R_240R_0402"
				(at 20.32 -12.7 0)
				(effects
					(font
						(size 1.27 1.27)
						(thickness 0.15)
					)
					(justify left bottom)
					(hide yes)
				)
			)
			(property "Footprint" "antmicro-footprints:R_0402_1005Metric"
				(at 20.32 -15.24 0)
				(effects
					(font
						(size 1.27 1.27)
						(thickness 0.15)
					)
					(justify left bottom)
					(hide yes)
				)
			)
			(property "Datasheet" "https://www.bourns.com/docs/product-datasheets/cr.pdf"
				(at 20.32 -17.78 0)
				(effects
					(font
						(size 1.27 1.27)
						(thickness 0.15)
					)
					(justify left bottom)
					(hide yes)
				)
			)
			(property "Description" "SMD Chip Resistor, 240 ohm, ± 1%, 63 mW, 0402 [1005 Metric], Thick Film, General Purpose"
				(at 0 0 0)
				(effects
					(font
						(size 1.27 1.27)
					)
					(hide yes)
				)
			)
			(property "MPN" "CR0402-FX-2400GLF"
				(at 20.32 -20.32 0)
				(effects
					(font
						(size 1.27 1.27)
						(thickness 0.15)
					)
					(justify left bottom)
					(hide yes)
				)
			)
			(property "Manufacturer" "Bourns"
				(at 20.32 -22.86 0)
				(effects
					(font
						(size 1.27 1.27)
						(thickness 0.15)
					)
					(justify left bottom)
					(hide yes)
				)
			)
			(property "License" "Apache-2.0"
				(at 20.32 -25.4 0)
				(effects
					(font
						(size 1.27 1.27)
						(thickness 0.15)
					)
					(justify left bottom)
					(hide yes)
				)
			)
			(property "Author" "Antmicro"
				(at 20.32 -27.94 0)
				(effects
					(font
						(size 1.27 1.27)
						(thickness 0.15)
					)
					(justify left bottom)
					(hide yes)
				)
			)
			(property "Val" "240R"
				(at 20.32 -7.62 0)
				(effects
					(font
						(size 1.27 1.27)
						(thickness 0.15)
					)
					(justify left bottom)
				)
			)
			(property "Tolerance" "1%"
				(at 20.32 -10.16 0)
				(effects
					(font
						(size 1.27 1.27)
					)
					(justify left bottom)
					(hide yes)
				)
			)
			(property "ki_keywords" "0402, SMT, RESISTOR, PASSIVE"
				(at 0 0 0)
				(effects
					(font
						(size 1.27 1.27)
					)
					(hide yes)
				)
			)
			(symbol "R_240R_0402_0_1"
				(rectangle
					(start 0.635 0.889)
					(end 4.445 -0.889)
					(stroke
						(width 0.254)
						(type default)
					)
					(fill
						(type none)
					)
				)
			)
			(symbol "R_240R_0402_1_1"
				(pin passive line
					(at 0 0 0)
					(length 0.635)
					(name "~"
						(effects
							(font
								(size 1.27 1.27)
							)
						)
					)
					(number "1"
						(effects
							(font
								(size 1.27 1.27)
							)
						)
					)
				)
				(pin passive line
					(at 5.08 0 180)
					(length 0.635)
					(name "~"
						(effects
							(font
								(size 1.27 1.27)
							)
						)
					)
					(number "2"
						(effects
							(font
								(size 1.27 1.27)
							)
						)
					)
				)
			)
		)
	(symbol "antmicroResistors0402:R_25k5_0402"
			(pin_numbers
				(hide yes)
			)
			(pin_names
				(hide yes)
			)
			(exclude_from_sim no)
			(in_bom yes)
			(on_board yes)
			(property "Reference" "R"
				(at 20.32 -5.08 0)
				(effects
					(font
						(size 1.27 1.27)
						(thickness 0.15)
					)
					(justify left bottom)
				)
			)
			(property "Value" "R_25k5_0402"
				(at 20.32 -12.7 0)
				(effects
					(font
						(size 1.27 1.27)
						(thickness 0.15)
					)
					(justify left bottom)
					(hide yes)
				)
			)
			(property "Footprint" "antmicro-footprints:R_0402_1005Metric"
				(at 20.32 -15.24 0)
				(effects
					(font
						(size 1.27 1.27)
						(thickness 0.15)
					)
					(justify left bottom)
					(hide yes)
				)
			)
			(property "Datasheet" "https://www.bourns.com/docs/product-datasheets/cr.pdf"
				(at 20.32 -17.78 0)
				(effects
					(font
						(size 1.27 1.27)
						(thickness 0.15)
					)
					(justify left bottom)
					(hide yes)
				)
			)
			(property "Description" "SMD Chip Resistor, Ceramic, 25.5 kohm, ± 1%, 62.5 mW, 0402 [1005 Metric], Thick Film"
				(at 0 0 0)
				(effects
					(font
						(size 1.27 1.27)
					)
					(hide yes)
				)
			)
			(property "MPN" "CR0402-FX-2552GLF"
				(at 20.32 -20.32 0)
				(effects
					(font
						(size 1.27 1.27)
						(thickness 0.15)
					)
					(justify left bottom)
					(hide yes)
				)
			)
			(property "Manufacturer" "Bourns"
				(at 20.32 -22.86 0)
				(effects
					(font
						(size 1.27 1.27)
						(thickness 0.15)
					)
					(justify left bottom)
					(hide yes)
				)
			)
			(property "License" "Apache-2.0"
				(at 20.32 -25.4 0)
				(effects
					(font
						(size 1.27 1.27)
						(thickness 0.15)
					)
					(justify left bottom)
					(hide yes)
				)
			)
			(property "Author" "Antmicro"
				(at 20.32 -27.94 0)
				(effects
					(font
						(size 1.27 1.27)
						(thickness 0.15)
					)
					(justify left bottom)
					(hide yes)
				)
			)
			(property "Val" "25k5"
				(at 20.32 -7.62 0)
				(effects
					(font
						(size 1.27 1.27)
						(thickness 0.15)
					)
					(justify left bottom)
				)
			)
			(property "Tolerance" "1%"
				(at 20.32 -10.16 0)
				(effects
					(font
						(size 1.27 1.27)
					)
					(justify left bottom)
					(hide yes)
				)
			)
			(property "ki_keywords" "0402, SMT, RESISTOR, PASSIVE"
				(at 0 0 0)
				(effects
					(font
						(size 1.27 1.27)
					)
					(hide yes)
				)
			)
			(symbol "R_25k5_0402_0_1"
				(rectangle
					(start 0.635 0.889)
					(end 4.445 -0.889)
					(stroke
						(width 0.254)
						(type default)
					)
					(fill
						(type none)
					)
				)
			)
			(symbol "R_25k5_0402_1_1"
				(pin passive line
					(at 0 0 0)
					(length 0.635)
					(name "~"
						(effects
							(font
								(size 1.27 1.27)
							)
						)
					)
					(number "1"
						(effects
							(font
								(size 1.27 1.27)
							)
						)
					)
				)
				(pin passive line
					(at 5.08 0 180)
					(length 0.635)
					(name "~"
						(effects
							(font
								(size 1.27 1.27)
							)
						)
					)
					(number "2"
						(effects
							(font
								(size 1.27 1.27)
							)
						)
					)
				)
			)
		)
	(symbol "antmicroResistors0402:R_3k9_0402"
			(pin_numbers
				(hide yes)
			)
			(pin_names
				(hide yes)
			)
			(exclude_from_sim no)
			(in_bom yes)
			(on_board yes)
			(property "Reference" "R"
				(at 20.32 -5.08 0)
				(effects
					(font
						(size 1.27 1.27)
						(thickness 0.15)
					)
					(justify left bottom)
				)
			)
			(property "Value" "R_3k9_0402"
				(at 20.32 -12.7 0)
				(effects
					(font
						(size 1.27 1.27)
						(thickness 0.15)
					)
					(justify left bottom)
					(hide yes)
				)
			)
			(property "Footprint" "antmicro-footprints:R_0402_1005Metric"
				(at 20.32 -15.24 0)
				(effects
					(font
						(size 1.27 1.27)
						(thickness 0.15)
					)
					(justify left bottom)
					(hide yes)
				)
			)
			(property "Datasheet" "https://www.bourns.com/docs/product-datasheets/cr.pdf"
				(at 20.32 -17.78 0)
				(effects
					(font
						(size 1.27 1.27)
						(thickness 0.15)
					)
					(justify left bottom)
					(hide yes)
				)
			)
			(property "Description" "SMD Chip Resistor, Ceramic, 3.9 kohm, ± 1%, 62.5 mW, 0402 [1005 Metric], Thick Film"
				(at 0 0 0)
				(effects
					(font
						(size 1.27 1.27)
					)
					(hide yes)
				)
			)
			(property "MPN" "CR0402-FX-3901GLF"
				(at 20.32 -20.32 0)
				(effects
					(font
						(size 1.27 1.27)
						(thickness 0.15)
					)
					(justify left bottom)
					(hide yes)
				)
			)
			(property "Manufacturer" "Bourns"
				(at 20.32 -22.86 0)
				(effects
					(font
						(size 1.27 1.27)
						(thickness 0.15)
					)
					(justify left bottom)
					(hide yes)
				)
			)
			(property "License" "Apache-2.0"
				(at 20.32 -25.4 0)
				(effects
					(font
						(size 1.27 1.27)
						(thickness 0.15)
					)
					(justify left bottom)
					(hide yes)
				)
			)
			(property "Author" "Antmicro"
				(at 20.32 -27.94 0)
				(effects
					(font
						(size 1.27 1.27)
						(thickness 0.15)
					)
					(justify left bottom)
					(hide yes)
				)
			)
			(property "Val" "3k9"
				(at 20.32 -7.62 0)
				(effects
					(font
						(size 1.27 1.27)
						(thickness 0.15)
					)
					(justify left bottom)
				)
			)
			(property "Tolerance" "1%"
				(at 20.32 -10.16 0)
				(effects
					(font
						(size 1.27 1.27)
					)
					(justify left bottom)
					(hide yes)
				)
			)
			(property "ki_keywords" "0402, SMT, RESISTOR, PASSIVE"
				(at 0 0 0)
				(effects
					(font
						(size 1.27 1.27)
					)
					(hide yes)
				)
			)
			(symbol "R_3k9_0402_0_1"
				(rectangle
					(start 0.635 0.889)
					(end 4.445 -0.889)
					(stroke
						(width 0.254)
						(type default)
					)
					(fill
						(type none)
					)
				)
			)
			(symbol "R_3k9_0402_1_1"
				(pin passive line
					(at 0 0 0)
					(length 0.635)
					(name "~"
						(effects
							(font
								(size 1.27 1.27)
							)
						)
					)
					(number "1"
						(effects
							(font
								(size 1.27 1.27)
							)
						)
					)
				)
				(pin passive line
					(at 5.08 0 180)
					(length 0.635)
					(name "~"
						(effects
							(font
								(size 1.27 1.27)
							)
						)
					)
					(number "2"
						(effects
							(font
								(size 1.27 1.27)
							)
						)
					)
				)
			)
		)
	(symbol "antmicroResistors0402:R_49k9_0402"
			(pin_numbers
				(hide yes)
			)
			(pin_names
				(hide yes)
			)
			(exclude_from_sim no)
			(in_bom yes)
			(on_board yes)
			(property "Reference" "R"
				(at 20.32 -5.08 0)
				(effects
					(font
						(size 1.27 1.27)
						(thickness 0.15)
					)
					(justify left bottom)
				)
			)
			(property "Value" "R_49k9_0402"
				(at 20.32 -12.7 0)
				(effects
					(font
						(size 1.27 1.27)
						(thickness 0.15)
					)
					(justify left bottom)
					(hide yes)
				)
			)
			(property "Footprint" "antmicro-footprints:R_0402_1005Metric"
				(at 20.32 -15.24 0)
				(effects
					(font
						(size 1.27 1.27)
						(thickness 0.15)
					)
					(justify left bottom)
					(hide yes)
				)
			)
			(property "Datasheet" "https://www.bourns.com/docs/product-datasheets/cr.pdf"
				(at 20.32 -17.78 0)
				(effects
					(font
						(size 1.27 1.27)
						(thickness 0.15)
					)
					(justify left bottom)
					(hide yes)
				)
			)
			(property "Description" "SMD Chip Resistor, 49.9 kohm, ± 1%, 63 mW, 0402 [1005 Metric], Thick Film, General Purpose"
				(at 0 0 0)
				(effects
					(font
						(size 1.27 1.27)
					)
					(hide yes)
				)
			)
			(property "MPN" "CR0402-FX-4992GLF"
				(at 20.32 -20.32 0)
				(effects
					(font
						(size 1.27 1.27)
						(thickness 0.15)
					)
					(justify left bottom)
					(hide yes)
				)
			)
			(property "Manufacturer" "Bourns"
				(at 20.32 -22.86 0)
				(effects
					(font
						(size 1.27 1.27)
						(thickness 0.15)
					)
					(justify left bottom)
					(hide yes)
				)
			)
			(property "License" "Apache-2.0"
				(at 20.32 -25.4 0)
				(effects
					(font
						(size 1.27 1.27)
						(thickness 0.15)
					)
					(justify left bottom)
					(hide yes)
				)
			)
			(property "Author" "Antmicro"
				(at 20.32 -27.94 0)
				(effects
					(font
						(size 1.27 1.27)
						(thickness 0.15)
					)
					(justify left bottom)
					(hide yes)
				)
			)
			(property "Val" "49k9"
				(at 20.32 -7.62 0)
				(effects
					(font
						(size 1.27 1.27)
						(thickness 0.15)
					)
					(justify left bottom)
				)
			)
			(property "Tolerance" "1%"
				(at 20.32 -10.16 0)
				(effects
					(font
						(size 1.27 1.27)
					)
					(justify left bottom)
					(hide yes)
				)
			)
			(property "ki_keywords" "0402, SMT, RESISTOR, PASSIVE"
				(at 0 0 0)
				(effects
					(font
						(size 1.27 1.27)
					)
					(hide yes)
				)
			)
			(symbol "R_49k9_0402_0_1"
				(rectangle
					(start 0.635 0.889)
					(end 4.445 -0.889)
					(stroke
						(width 0.254)
						(type default)
					)
					(fill
						(type none)
					)
				)
			)
			(symbol "R_49k9_0402_1_1"
				(pin passive line
					(at 0 0 0)
					(length 0.635)
					(name "~"
						(effects
							(font
								(size 1.27 1.27)
							)
						)
					)
					(number "1"
						(effects
							(font
								(size 1.27 1.27)
							)
						)
					)
				)
				(pin passive line
					(at 5.08 0 180)
					(length 0.635)
					(name "~"
						(effects
							(font
								(size 1.27 1.27)
							)
						)
					)
					(number "2"
						(effects
							(font
								(size 1.27 1.27)
							)
						)
					)
				)
			)
		)
	(symbol "antmicroResistors0603:R_0R_22.4A_0603"
			(pin_numbers
				(hide yes)
			)
			(pin_names
				(hide yes)
			)
			(exclude_from_sim no)
			(in_bom yes)
			(on_board yes)
			(property "Reference" "R"
				(at 15.24 -2.54 0)
				(effects
					(font
						(size 1.27 1.27)
						(thickness 0.15)
					)
					(justify left bottom)
				)
			)
			(property "Value" "R_0R_22.4A_0603"
				(at 15.24 -5.08 0)
				(effects
					(font
						(size 1.27 1.27)
						(thickness 0.15)
					)
					(justify left bottom)
				)
			)
			(property "Footprint" "antmicro-footprints:R_0603_1608Metric"
				(at 15.24 -10.16 0)
				(effects
					(font
						(size 1.27 1.27)
						(thickness 0.15)
					)
					(justify left bottom)
					(hide yes)
				)
			)
			(property "Datasheet" "https://fscdn.rohm.com/en/products/databook/datasheet/passive/resistor/chip_resistor/pmr-jpw-e.pdf"
				(at 15.24 -12.7 0)
				(effects
					(font
						(size 1.27 1.27)
						(thickness 0.15)
					)
					(justify left bottom)
					(hide yes)
				)
			)
			(property "Description" "SMD Chip Resistor"
				(at 0 0 0)
				(effects
					(font
						(size 1.27 1.27)
					)
					(hide yes)
				)
			)
			(property "MPN" "PMR03EZPJ000"
				(at 15.24 -15.24 0)
				(effects
					(font
						(size 1.27 1.27)
						(thickness 0.15)
					)
					(justify left bottom)
					(hide yes)
				)
			)
			(property "Manufacturer" "ROHM Semiconductor"
				(at 15.24 -17.78 0)
				(effects
					(font
						(size 1.27 1.27)
						(thickness 0.15)
					)
					(justify left bottom)
					(hide yes)
				)
			)
			(property "Val" "0R"
				(at 15.24 -7.62 0)
				(effects
					(font
						(size 1.27 1.27)
						(thickness 0.15)
					)
					(justify left bottom)
				)
			)
			(property "Max. Curr." "22.4A"
				(at 15.24 -20.32 0)
				(effects
					(font
						(size 1.27 1.27)
						(thickness 0.15)
					)
					(justify left bottom)
				)
			)
			(property "Author" "Antmicro"
				(at 15.24 -22.86 0)
				(effects
					(font
						(size 1.27 1.27)
						(thickness 0.15)
					)
					(justify left bottom)
					(hide yes)
				)
			)
			(property "License" "Apache-2.0"
				(at 15.24 -25.4 0)
				(effects
					(font
						(size 1.27 1.27)
						(thickness 0.15)
					)
					(justify left bottom)
					(hide yes)
				)
			)
			(property "Tolerance" "template_tolerance"
				(at 20.32 -10.16 0)
				(effects
					(font
						(size 1.27 1.27)
					)
					(justify left bottom)
					(hide yes)
				)
			)
			(property "ki_keywords" "0603, SMT, RESISTOR, PASSIVE"
				(at 0 0 0)
				(effects
					(font
						(size 1.27 1.27)
					)
					(hide yes)
				)
			)
			(symbol "R_0R_22.4A_0603_0_1"
				(rectangle
					(start 0.635 0.889)
					(end 4.445 -0.889)
					(stroke
						(width 0.254)
						(type default)
					)
					(fill
						(type none)
					)
				)
			)
			(symbol "R_0R_22.4A_0603_1_1"
				(pin passive line
					(at 0 0 0)
					(length 0.635)
					(name "~"
						(effects
							(font
								(size 1.27 1.27)
							)
						)
					)
					(number "1"
						(effects
							(font
								(size 1.27 1.27)
							)
						)
					)
				)
				(pin passive line
					(at 5.08 0 180)
					(length 0.635)
					(name "~"
						(effects
							(font
								(size 1.27 1.27)
							)
						)
					)
					(number "2"
						(effects
							(font
								(size 1.27 1.27)
							)
						)
					)
				)
			)
		)
	(symbol "antmicroTVSDiodes:PTVS48VS1UR,115"
			(pin_numbers
				(hide yes)
			)
			(pin_names
				(hide yes)
			)
			(exclude_from_sim no)
			(in_bom yes)
			(on_board yes)
			(property "Reference" "D"
				(at 21.59 -5.08 0)
				(effects
					(font
						(size 1.27 1.27)
						(thickness 0.15)
					)
					(justify left bottom)
				)
			)
			(property "Value" "PTVS48VS1UR"
				(at 21.59 -7.62 0)
				(effects
					(font
						(size 1.27 1.27)
						(thickness 0.15)
					)
					(justify left bottom)
				)
			)
			(property "Footprint" "antmicro-footprints:D_SOD-123F"
				(at 21.59 -10.16 0)
				(effects
					(font
						(size 1.27 1.27)
						(thickness 0.15)
					)
					(justify left bottom)
					(hide yes)
				)
			)
			(property "Datasheet" "https://www.mouser.com/datasheet/2/916/PTVSXS1UR_SER-1545507.pdf"
				(at 21.59 -12.7 0)
				(effects
					(font
						(size 1.27 1.27)
						(thickness 0.15)
					)
					(justify left bottom)
					(hide yes)
				)
			)
			(property "Description" "Rectifier diode"
				(at 0 0 0)
				(effects
					(font
						(size 1.27 1.27)
					)
					(hide yes)
				)
			)
			(property "MPN" "PTVS48VS1UR,115"
				(at 21.59 -15.24 0)
				(effects
					(font
						(size 1.27 1.27)
						(thickness 0.15)
					)
					(justify left bottom)
					(hide yes)
				)
			)
			(property "Manufacturer" "Nexperia"
				(at 21.59 -17.78 0)
				(effects
					(font
						(size 1.27 1.27)
						(thickness 0.15)
					)
					(justify left bottom)
					(hide yes)
				)
			)
			(property "Author" "Antmicro"
				(at 21.59 -20.32 0)
				(effects
					(font
						(size 1.27 1.27)
						(thickness 0.15)
					)
					(justify left bottom)
					(hide yes)
				)
			)
			(property "License" "Apache-2.0"
				(at 21.59 -22.86 0)
				(effects
					(font
						(size 1.27 1.27)
						(thickness 0.15)
					)
					(justify left bottom)
					(hide yes)
				)
			)
			(property "ki_keywords" "SMT, DIODE, SEMICONDUCTOR, TVS, ESD"
				(at 0 0 0)
				(effects
					(font
						(size 1.27 1.27)
					)
					(hide yes)
				)
			)
			(symbol "PTVS48VS1UR,115_0_1"
				(polyline
					(pts
						(xy 5.715 1.905) (xy 5.08 1.27) (xy 5.08 -1.27) (xy 4.445 -1.905)
					)
					(stroke
						(width 0.254)
						(type default)
					)
					(fill
						(type none)
					)
				)
			)
			(symbol "PTVS48VS1UR,115_1_1"
				(polyline
					(pts
						(xy 2.54 1.27) (xy 2.54 -1.27) (xy 5.08 0) (xy 2.54 1.27)
					)
					(stroke
						(width 0.254)
						(type default)
					)
					(fill
						(type outline)
					)
				)
				(pin passive line
					(at 0 0 0)
					(length 2.54)
					(name "A"
						(effects
							(font
								(size 1.27 1.27)
							)
						)
					)
					(number "A"
						(effects
							(font
								(size 1.27 1.27)
							)
						)
					)
				)
				(pin passive line
					(at 7.62 0 180)
					(length 2.54)
					(name "C"
						(effects
							(font
								(size 1.27 1.27)
							)
						)
					)
					(number "K"
						(effects
							(font
								(size 1.27 1.27)
							)
						)
					)
				)
			)
		)
	(symbol "antmicroTestPoints:TP_0.75mm_SMD"
			(pin_names
				(hide yes)
			)
			(exclude_from_sim no)
			(in_bom no)
			(on_board yes)
			(property "Reference" "TP"
				(at 10.795 -1.27 0)
				(effects
					(font
						(size 1.27 1.27)
						(thickness 0.15)
					)
					(justify left bottom)
				)
			)
			(property "Value" "TP_0.75mm_SMD"
				(at 10.795 -3.81 0)
				(effects
					(font
						(size 1.27 1.27)
						(thickness 0.15)
					)
					(justify left bottom)
					(hide yes)
				)
			)
			(property "Footprint" "antmicro-footprints:TP_SMD_0.75mm"
				(at 10.795 -6.35 0)
				(effects
					(font
						(size 1.27 1.27)
						(thickness 0.15)
					)
					(justify left bottom)
					(hide yes)
				)
			)
			(property "Datasheet" ""
				(at 17.78 -12.7 0)
				(effects
					(font
						(size 1.27 1.27)
						(thickness 0.15)
					)
					(justify left bottom)
					(hide yes)
				)
			)
			(property "Description" "SMT test point"
				(at 0 0 0)
				(effects
					(font
						(size 1.27 1.27)
					)
					(hide yes)
				)
			)
			(property "MPN" ""
				(at 10.795 -11.43 0)
				(effects
					(font
						(size 1.27 1.27)
						(thickness 0.15)
					)
					(justify left bottom)
					(hide yes)
				)
			)
			(property "Manufacturer" ""
				(at 10.795 -6.35 0)
				(effects
					(font
						(size 1.27 1.27)
						(thickness 0.15)
					)
					(justify left bottom)
					(hide yes)
				)
			)
			(property "Author" "Antmicro"
				(at 10.795 -8.89 0)
				(effects
					(font
						(size 1.27 1.27)
						(thickness 0.15)
					)
					(justify left bottom)
					(hide yes)
				)
			)
			(property "License" "Apache-2.0"
				(at 10.795 -11.43 0)
				(effects
					(font
						(size 1.27 1.27)
						(thickness 0.15)
					)
					(justify left bottom)
					(hide yes)
				)
			)
			(property "ki_keywords" "TESTPOINT"
				(at 0 0 0)
				(effects
					(font
						(size 1.27 1.27)
					)
					(hide yes)
				)
			)
			(symbol "TP_0.75mm_SMD_1_1"
				(circle
					(center 3.175 0)
					(radius 0.635)
					(stroke
						(width 0.254)
						(type default)
					)
					(fill
						(type none)
					)
				)
				(pin passive line
					(at 0 0 0)
					(length 2.54)
					(name "1"
						(effects
							(font
								(size 1.27 1.27)
							)
						)
					)
					(number "1"
						(effects
							(font
								(size 1.27 1.27)
							)
						)
					)
				)
			)
		)
	(symbol "antmicroTestPoints:TP_1mm_SMD"
			(pin_names
				(hide yes)
			)
			(exclude_from_sim no)
			(in_bom no)
			(on_board yes)
			(property "Reference" "TP"
				(at 15.24 -5.08 0)
				(effects
					(font
						(size 1.27 1.27)
						(thickness 0.15)
					)
					(justify left bottom)
				)
			)
			(property "Value" "TP_1mm_SMD"
				(at 15.24 -7.62 0)
				(effects
					(font
						(size 1.27 1.27)
						(thickness 0.15)
					)
					(justify left bottom)
					(hide yes)
				)
			)
			(property "Footprint" "antmicro-footprints:TP_SMD_1mm"
				(at 15.24 -10.16 0)
				(effects
					(font
						(size 1.27 1.27)
						(thickness 0.15)
					)
					(justify left bottom)
					(hide yes)
				)
			)
			(property "Datasheet" ""
				(at 17.78 -12.7 0)
				(effects
					(font
						(size 1.27 1.27)
						(thickness 0.15)
					)
					(justify left bottom)
					(hide yes)
				)
			)
			(property "Description" "Test point 1mm SMD"
				(at 0 0 0)
				(effects
					(font
						(size 1.27 1.27)
					)
					(hide yes)
				)
			)
			(property "MPN" ""
				(at 0 0 0)
				(effects
					(font
						(size 1.27 1.27)
					)
					(hide yes)
				)
			)
			(property "Manufacturer" ""
				(at 0 0 0)
				(effects
					(font
						(size 1.27 1.27)
					)
					(hide yes)
				)
			)
			(property "Author" "Antmicro"
				(at 15.24 -15.24 0)
				(effects
					(font
						(size 1.27 1.27)
						(thickness 0.15)
					)
					(justify left bottom)
					(hide yes)
				)
			)
			(property "License" "Apache-2.0"
				(at 15.24 -17.78 0)
				(effects
					(font
						(size 1.27 1.27)
						(thickness 0.15)
					)
					(justify left bottom)
					(hide yes)
				)
			)
			(property "ki_keywords" "TESTPOINT"
				(at 0 0 0)
				(effects
					(font
						(size 1.27 1.27)
					)
					(hide yes)
				)
			)
			(symbol "TP_1mm_SMD_1_1"
				(circle
					(center 3.175 0)
					(radius 0.635)
					(stroke
						(width 0.254)
						(type default)
					)
					(fill
						(type none)
					)
				)
				(pin passive line
					(at 0 0 0)
					(length 2.54)
					(name "1"
						(effects
							(font
								(size 1.27 1.27)
							)
						)
					)
					(number "1"
						(effects
							(font
								(size 1.27 1.27)
							)
						)
					)
				)
			)
		)
	(symbol "antmicroTransistorsFETsMOSFETsSingle:DMG1012T-7"
			(pin_names
				(offset 0)
			)
			(exclude_from_sim no)
			(in_bom no)
			(on_board yes)
			(property "Reference" "Q"
				(at 10.16 3.81 0)
				(effects
					(font
						(size 1.27 1.27)
						(thickness 0.15)
					)
					(justify left bottom)
				)
			)
			(property "Value" "DMG1012T-7"
				(at 10.16 -3.81 0)
				(effects
					(font
						(size 1.27 1.27)
						(thickness 0.15)
					)
					(justify left bottom)
					(hide yes)
				)
			)
			(property "Footprint" "antmicro-footprints:SOT-523"
				(at 10.16 -6.35 0)
				(effects
					(font
						(size 1.27 1.27)
						(thickness 0.15)
					)
					(justify left bottom)
					(hide yes)
				)
			)
			(property "Datasheet" "https://www.diodes.com/assets/Datasheets/ds31783.pdf"
				(at 10.16 -8.89 0)
				(effects
					(font
						(size 1.27 1.27)
						(thickness 0.15)
					)
					(justify left bottom)
					(hide yes)
				)
			)
			(property "Description" "Power MOSFET, N Channel, 20 V, 630 mA, 0.3 ohm, SOT-523, Surface Mount"
				(at 0 0 0)
				(effects
					(font
						(size 1.27 1.27)
					)
					(hide yes)
				)
			)
			(property "MPN" "DMG1012T-7"
				(at 10.16 1.27 0)
				(effects
					(font
						(size 1.27 1.27)
						(thickness 0.15)
					)
					(justify left bottom)
				)
			)
			(property "Manufacturer" "Diodes Incorporated"
				(at 10.16 -1.27 0)
				(effects
					(font
						(size 1.27 1.27)
						(thickness 0.15)
					)
					(justify left bottom)
					(hide yes)
				)
			)
			(property "Author" "Antmicro"
				(at 10.16 -11.43 0)
				(effects
					(font
						(size 1.27 1.27)
						(thickness 0.15)
					)
					(justify left bottom)
					(hide yes)
				)
			)
			(property "License" "Apache-2.0"
				(at 10.16 -13.97 0)
				(effects
					(font
						(size 1.27 1.27)
						(thickness 0.15)
					)
					(justify left bottom)
					(hide yes)
				)
			)
			(property "ki_keywords" "SMT, MOSFET, SEMICONDUCTOR"
				(at 0 0 0)
				(effects
					(font
						(size 1.27 1.27)
					)
					(hide yes)
				)
			)
			(symbol "DMG1012T-7_1_1"
				(polyline
					(pts
						(xy 1.27 0) (xy 3.302 0) (xy 3.302 3.937)
					)
					(stroke
						(width 0.254)
						(type default)
					)
					(fill
						(type none)
					)
				)
				(polyline
					(pts
						(xy 3.81 4.445) (xy 3.81 3.429)
					)
					(stroke
						(width 0.254)
						(type default)
					)
					(fill
						(type background)
					)
				)
				(polyline
					(pts
						(xy 3.81 2.54) (xy 3.81 3.048)
					)
					(stroke
						(width 0.254)
						(type default)
					)
					(fill
						(type background)
					)
				)
				(polyline
					(pts
						(xy 3.81 2.54) (xy 3.81 2.032)
					)
					(stroke
						(width 0.254)
						(type default)
					)
					(fill
						(type background)
					)
				)
				(polyline
					(pts
						(xy 3.81 2.54) (xy 4.572 3.048) (xy 4.572 2.032) (xy 3.81 2.54)
					)
					(stroke
						(width 0.254)
						(type default)
					)
					(fill
						(type outline)
					)
				)
				(polyline
					(pts
						(xy 3.81 1.143) (xy 3.81 1.651)
					)
					(stroke
						(width 0.254)
						(type default)
					)
					(fill
						(type background)
					)
				)
				(polyline
					(pts
						(xy 3.81 1.143) (xy 3.81 0.635)
					)
					(stroke
						(width 0.254)
						(type default)
					)
					(fill
						(type background)
					)
				)
				(circle
					(center 5.08 2.54)
					(radius 3.302)
					(stroke
						(width 0.254)
						(type default)
					)
					(fill
						(type background)
					)
				)
				(polyline
					(pts
						(xy 6.223 0.635) (xy 7.366 0.635) (xy 7.366 3.937) (xy 7.366 4.445) (xy 6.223 4.445)
					)
					(stroke
						(width 0.254)
						(type default)
					)
					(fill
						(type none)
					)
				)
				(polyline
					(pts
						(xy 6.35 6.35) (xy 6.35 3.937) (xy 3.81 3.937)
					)
					(stroke
						(width 0.254)
						(type default)
					)
					(fill
						(type none)
					)
				)
				(circle
					(center 6.35 4.445)
					(radius 0.127)
					(stroke
						(width 0.254)
						(type default)
					)
					(fill
						(type background)
					)
				)
				(polyline
					(pts
						(xy 6.35 1.143) (xy 3.81 1.143)
					)
					(stroke
						(width 0.254)
						(type default)
					)
					(fill
						(type background)
					)
				)
				(circle
					(center 6.35 1.143)
					(radius 0.127)
					(stroke
						(width 0.254)
						(type default)
					)
					(fill
						(type background)
					)
				)
				(circle
					(center 6.35 0.635)
					(radius 0.127)
					(stroke
						(width 0.254)
						(type default)
					)
					(fill
						(type background)
					)
				)
				(polyline
					(pts
						(xy 6.35 -1.27) (xy 6.35 2.54) (xy 3.81 2.54)
					)
					(stroke
						(width 0.254)
						(type default)
					)
					(fill
						(type none)
					)
				)
				(polyline
					(pts
						(xy 7.366 3.048) (xy 6.858 2.286) (xy 7.874 2.286) (xy 7.366 3.048)
					)
					(stroke
						(width 0.254)
						(type default)
					)
					(fill
						(type outline)
					)
				)
				(polyline
					(pts
						(xy 7.874 3.048) (xy 6.858 3.048)
					)
					(stroke
						(width 0.254)
						(type default)
					)
					(fill
						(type background)
					)
				)
				(pin bidirectional line
					(at 0 0 0)
					(length 2.54)
					(name "G"
						(effects
							(font
								(size 1.27 1.27)
							)
						)
					)
					(number "1"
						(effects
							(font
								(size 1.27 1.27)
							)
						)
					)
				)
				(pin bidirectional line
					(at 6.35 7.62 270)
					(length 2.54)
					(name "D"
						(effects
							(font
								(size 1.27 1.27)
							)
						)
					)
					(number "3"
						(effects
							(font
								(size 1.27 1.27)
							)
						)
					)
				)
				(pin bidirectional line
					(at 6.35 -2.54 90)
					(length 2.54)
					(name "S"
						(effects
							(font
								(size 1.27 1.27)
							)
						)
					)
					(number "2"
						(effects
							(font
								(size 1.27 1.27)
							)
						)
					)
				)
			)
		)
	(symbol "antmicroTrimmerPotentiometers:TC33X-2-203E"
			(pin_names
				(hide yes)
			)
			(exclude_from_sim no)
			(in_bom yes)
			(on_board yes)
			(property "Reference" "POT"
				(at 15.24 0 0)
				(effects
					(font
						(size 1.27 1.27)
						(thickness 0.15)
					)
					(justify left bottom)
				)
			)
			(property "Value" "TC33X-2-203E"
				(at 15.24 -2.54 0)
				(effects
					(font
						(size 1.27 1.27)
						(thickness 0.15)
					)
					(justify left bottom)
				)
			)
			(property "Footprint" "antmicro-footprints:Trimpot_3.8mmx3.6mm_TC33X-2-103E"
				(at 15.24 -5.08 0)
				(effects
					(font
						(size 1.27 1.27)
						(thickness 0.15)
					)
					(justify left bottom)
					(hide yes)
				)
			)
			(property "Datasheet" "https://www.bourns.com/docs/Product-Datasheets/TC33.pdf"
				(at 15.24 -7.62 0)
				(effects
					(font
						(size 1.27 1.27)
						(thickness 0.15)
					)
					(justify left bottom)
					(hide yes)
				)
			)
			(property "Description" "Trimmer potentiometer"
				(at 0 0 0)
				(effects
					(font
						(size 1.27 1.27)
					)
					(hide yes)
				)
			)
			(property "MPN" "TC33X-2-203E"
				(at 15.24 -10.16 0)
				(effects
					(font
						(size 1.27 1.27)
						(thickness 0.15)
					)
					(justify left bottom)
					(hide yes)
				)
			)
			(property "Manufacturer" "Bourns"
				(at 15.24 -12.7 0)
				(effects
					(font
						(size 1.27 1.27)
						(thickness 0.15)
					)
					(justify left bottom)
					(hide yes)
				)
			)
			(property "Author" "Antmicro"
				(at 15.24 -15.24 0)
				(effects
					(font
						(size 1.27 1.27)
						(thickness 0.15)
					)
					(justify left bottom)
					(hide yes)
				)
			)
			(property "License" "Apache-2.0"
				(at 15.24 -17.78 0)
				(effects
					(font
						(size 1.27 1.27)
						(thickness 0.15)
					)
					(justify left bottom)
					(hide yes)
				)
			)
			(property "ki_keywords" "SMT, RESISTOR, PASSIVE, POTENTIOMETER"
				(at 0 0 0)
				(effects
					(font
						(size 1.27 1.27)
					)
					(hide yes)
				)
			)
			(symbol "TC33X-2-203E_0_1"
				(rectangle
					(start 1.27 1.016)
					(end 6.35 -1.016)
					(stroke
						(width 0.254)
						(type default)
					)
					(fill
						(type none)
					)
				)
				(polyline
					(pts
						(xy 3.048 1.524) (xy 4.572 1.524)
					)
					(stroke
						(width 0)
						(type default)
					)
					(fill
						(type none)
					)
				)
				(polyline
					(pts
						(xy 3.81 2.54) (xy 3.81 1.524)
					)
					(stroke
						(width 0)
						(type default)
					)
					(fill
						(type none)
					)
				)
			)
			(symbol "TC33X-2-203E_1_1"
				(pin passive line
					(at 0 0 0)
					(length 1.27)
					(name "1"
						(effects
							(font
								(size 1.27 1.27)
							)
						)
					)
					(number "1"
						(effects
							(font
								(size 1.27 1.27)
							)
						)
					)
				)
				(pin passive line
					(at 3.81 3.81 270)
					(length 1.27)
					(name "2"
						(effects
							(font
								(size 1.27 1.27)
							)
						)
					)
					(number "2"
						(effects
							(font
								(size 1.27 1.27)
							)
						)
					)
				)
				(pin passive line
					(at 7.62 0 180)
					(length 1.27)
					(name "3"
						(effects
							(font
								(size 1.27 1.27)
							)
						)
					)
					(number "3"
						(effects
							(font
								(size 1.27 1.27)
							)
						)
					)
				)
			)
		)
	(symbol "antmicroWire2BoardConnectors:JST_SH_1x4_SM04B-SRSS-TB-LF-SN"
			(pin_names
				(hide yes)
			)
			(exclude_from_sim no)
			(in_bom yes)
			(on_board yes)
			(property "Reference" "J"
				(at 26.67 -2.54 0)
				(effects
					(font
						(size 1.27 1.27)
						(thickness 0.15)
					)
					(justify left bottom)
				)
			)
			(property "Value" "JST_SH_1x4_SM04B-SRSS-TB-LF-SN"
				(at 26.67 -7.62 0)
				(effects
					(font
						(size 1.27 1.27)
						(thickness 0.15)
					)
					(justify left bottom)
					(hide yes)
				)
			)
			(property "Footprint" "antmicro-footprints:Conn_JST_SH_1x4_SM04B-SRSS-TB-LF-SN"
				(at 26.67 -10.16 0)
				(effects
					(font
						(size 1.27 1.27)
						(thickness 0.15)
					)
					(justify left bottom)
					(hide yes)
				)
			)
			(property "Datasheet" "https://www.jst-mfg.com/product/pdf/eng/eSH.pdf"
				(at 26.67 -12.7 0)
				(effects
					(font
						(size 1.27 1.27)
						(thickness 0.15)
					)
					(justify left bottom)
					(hide yes)
				)
			)
			(property "Description" "Pin Header, Right Angle, Wire-to-Board, 1 mm, 1 Rows, 4 Contacts, Surface Mount Right Angle, SH"
				(at 0 0 0)
				(effects
					(font
						(size 1.27 1.27)
					)
					(hide yes)
				)
			)
			(property "MPN" "SM04B-SRSS-TB(LF)(SN)"
				(at 26.67 -5.08 0)
				(effects
					(font
						(size 1.27 1.27)
						(thickness 0.15)
					)
					(justify left bottom)
				)
			)
			(property "Manufacturer" "JST Automotive Connectors"
				(at 26.67 -15.24 0)
				(effects
					(font
						(size 1.27 1.27)
						(thickness 0.15)
					)
					(justify left bottom)
					(hide yes)
				)
			)
			(property "Author" "Antmicro"
				(at 26.67 -17.78 0)
				(effects
					(font
						(size 1.27 1.27)
						(thickness 0.15)
					)
					(justify left bottom)
					(hide yes)
				)
			)
			(property "License" "Apache-2.0"
				(at 26.67 -20.32 0)
				(effects
					(font
						(size 1.27 1.27)
						(thickness 0.15)
					)
					(justify left bottom)
					(hide yes)
				)
			)
			(property "ki_keywords" "VERTICAL, SMT, WIRE-BOARD, CONNECTOR, MALE, HEADER"
				(at 0 0 0)
				(effects
					(font
						(size 1.27 1.27)
					)
					(hide yes)
				)
			)
			(symbol "JST_SH_1x4_SM04B-SRSS-TB-LF-SN_1_1"
				(rectangle
					(start 3.81 1.27)
					(end 6.35 -13.97)
					(stroke
						(width 0.254)
						(type default)
					)
					(fill
						(type background)
					)
				)
				(rectangle
					(start 3.81 0.127)
					(end 5.08 -0.127)
					(stroke
						(width 0.254)
						(type default)
					)
					(fill
						(type background)
					)
				)
				(rectangle
					(start 3.81 -2.413)
					(end 5.08 -2.667)
					(stroke
						(width 0.254)
						(type default)
					)
					(fill
						(type background)
					)
				)
				(rectangle
					(start 3.81 -4.953)
					(end 5.08 -5.207)
					(stroke
						(width 0.254)
						(type default)
					)
					(fill
						(type background)
					)
				)
				(rectangle
					(start 3.81 -7.493)
					(end 5.08 -7.747)
					(stroke
						(width 0.254)
						(type default)
					)
					(fill
						(type background)
					)
				)
				(rectangle
					(start 3.81 -10.033)
					(end 5.08 -10.287)
					(stroke
						(width 0.254)
						(type default)
					)
					(fill
						(type background)
					)
				)
				(rectangle
					(start 3.81 -12.573)
					(end 5.08 -12.827)
					(stroke
						(width 0.254)
						(type default)
					)
					(fill
						(type background)
					)
				)
				(pin passive line
					(at 0 0 0)
					(length 3.81)
					(name "1"
						(effects
							(font
								(size 1.27 1.27)
							)
						)
					)
					(number "1"
						(effects
							(font
								(size 1.27 1.27)
							)
						)
					)
				)
				(pin passive line
					(at 0 -2.54 0)
					(length 3.81)
					(name "2"
						(effects
							(font
								(size 1.27 1.27)
							)
						)
					)
					(number "2"
						(effects
							(font
								(size 1.27 1.27)
							)
						)
					)
				)
				(pin passive line
					(at 0 -5.08 0)
					(length 3.81)
					(name "3"
						(effects
							(font
								(size 1.27 1.27)
							)
						)
					)
					(number "3"
						(effects
							(font
								(size 1.27 1.27)
							)
						)
					)
				)
				(pin passive line
					(at 0 -7.62 0)
					(length 3.81)
					(name "4"
						(effects
							(font
								(size 1.27 1.27)
							)
						)
					)
					(number "4"
						(effects
							(font
								(size 1.27 1.27)
							)
						)
					)
				)
				(pin passive line
					(at 0 -10.16 0)
					(length 3.81)
					(name "SH1"
						(effects
							(font
								(size 1.27 1.27)
							)
						)
					)
					(number "SH1"
						(effects
							(font
								(size 1.27 1.27)
							)
						)
					)
				)
				(pin passive line
					(at 0 -12.7 0)
					(length 3.81)
					(name "SH2"
						(effects
							(font
								(size 1.27 1.27)
							)
						)
					)
					(number "SH2"
						(effects
							(font
								(size 1.27 1.27)
							)
						)
					)
				)
			)
		)
	(symbol "antmicropower:+0V5"
			(power)
			(pin_names
				(offset 0)
			)
			(exclude_from_sim no)
			(in_bom yes)
			(on_board yes)
			(property "Reference" "#PWR"
				(at 0 -3.81 0)
				(effects
					(font
						(size 1.27 1.27)
					)
					(hide yes)
				)
			)
			(property "Value" "+0V5"
				(at 0 3.556 0)
				(effects
					(font
						(size 1.27 1.27)
					)
				)
			)
			(property "Footprint" ""
				(at 0 0 0)
				(effects
					(font
						(size 1.27 1.27)
					)
					(hide yes)
				)
			)
			(property "Datasheet" ""
				(at 0 0 0)
				(effects
					(font
						(size 1.27 1.27)
					)
					(hide yes)
				)
			)
			(property "Description" ""
				(at 0 0 0)
				(effects
					(font
						(size 1.27 1.27)
					)
					(hide yes)
				)
			)
			(symbol "+0V5_0_1"
				(polyline
					(pts
						(xy -0.762 1.27) (xy 0 2.54)
					)
					(stroke
						(width 0)
						(type default)
					)
					(fill
						(type none)
					)
				)
				(polyline
					(pts
						(xy 0 2.54) (xy 0.762 1.27)
					)
					(stroke
						(width 0)
						(type default)
					)
					(fill
						(type none)
					)
				)
				(polyline
					(pts
						(xy 0 0) (xy 0 2.54)
					)
					(stroke
						(width 0)
						(type default)
					)
					(fill
						(type none)
					)
				)
			)
			(symbol "+0V5_1_1"
				(pin power_in line
					(at 0 0 90)
					(length 0)
					(hide yes)
					(name "+0V5"
						(effects
							(font
								(size 1.27 1.27)
							)
						)
					)
					(number "1"
						(effects
							(font
								(size 1.27 1.27)
							)
						)
					)
				)
			)
		)
	(symbol "antmicropower:+0V9"
			(power)
			(pin_names
				(offset 0)
			)
			(exclude_from_sim no)
			(in_bom yes)
			(on_board yes)
			(property "Reference" "#PWR"
				(at 0 -3.81 0)
				(effects
					(font
						(size 1.27 1.27)
					)
					(hide yes)
				)
			)
			(property "Value" "+0V9"
				(at 0 3.556 0)
				(effects
					(font
						(size 1.27 1.27)
					)
				)
			)
			(property "Footprint" ""
				(at 0 0 0)
				(effects
					(font
						(size 1.27 1.27)
					)
					(hide yes)
				)
			)
			(property "Datasheet" ""
				(at 0 0 0)
				(effects
					(font
						(size 1.27 1.27)
					)
					(hide yes)
				)
			)
			(property "Description" ""
				(at 0 0 0)
				(effects
					(font
						(size 1.27 1.27)
					)
					(hide yes)
				)
			)
			(symbol "+0V9_0_1"
				(polyline
					(pts
						(xy -0.762 1.27) (xy 0 2.54)
					)
					(stroke
						(width 0)
						(type default)
					)
					(fill
						(type none)
					)
				)
				(polyline
					(pts
						(xy 0 2.54) (xy 0.762 1.27)
					)
					(stroke
						(width 0)
						(type default)
					)
					(fill
						(type none)
					)
				)
				(polyline
					(pts
						(xy 0 0) (xy 0 2.54)
					)
					(stroke
						(width 0)
						(type default)
					)
					(fill
						(type none)
					)
				)
			)
			(symbol "+0V9_1_1"
				(pin power_in line
					(at 0 0 90)
					(length 0)
					(hide yes)
					(name "+0V9"
						(effects
							(font
								(size 1.27 1.27)
							)
						)
					)
					(number "1"
						(effects
							(font
								(size 1.27 1.27)
							)
						)
					)
				)
			)
		)
	(symbol "antmicropower:+1V05"
			(power)
			(pin_names
				(offset 0)
			)
			(exclude_from_sim no)
			(in_bom yes)
			(on_board yes)
			(property "Reference" "#PWR"
				(at 0 -3.81 0)
				(effects
					(font
						(size 1.27 1.27)
					)
					(hide yes)
				)
			)
			(property "Value" "+1V05"
				(at 0 3.556 0)
				(effects
					(font
						(size 1.27 1.27)
					)
				)
			)
			(property "Footprint" ""
				(at 0 0 0)
				(effects
					(font
						(size 1.27 1.27)
					)
					(hide yes)
				)
			)
			(property "Datasheet" ""
				(at 0 0 0)
				(effects
					(font
						(size 1.27 1.27)
					)
					(hide yes)
				)
			)
			(property "Description" ""
				(at 0 0 0)
				(effects
					(font
						(size 1.27 1.27)
					)
					(hide yes)
				)
			)
			(symbol "+1V05_0_1"
				(polyline
					(pts
						(xy -0.762 1.27) (xy 0 2.54)
					)
					(stroke
						(width 0)
						(type default)
					)
					(fill
						(type none)
					)
				)
				(polyline
					(pts
						(xy 0 2.54) (xy 0.762 1.27)
					)
					(stroke
						(width 0)
						(type default)
					)
					(fill
						(type none)
					)
				)
				(polyline
					(pts
						(xy 0 0) (xy 0 2.54)
					)
					(stroke
						(width 0)
						(type default)
					)
					(fill
						(type none)
					)
				)
			)
			(symbol "+1V05_1_1"
				(pin power_in line
					(at 0 0 90)
					(length 0)
					(hide yes)
					(name "+1V05"
						(effects
							(font
								(size 1.27 1.27)
							)
						)
					)
					(number "1"
						(effects
							(font
								(size 1.27 1.27)
							)
						)
					)
				)
			)
		)
	(symbol "antmicropower:+1V1"
			(power)
			(pin_names
				(offset 0)
			)
			(exclude_from_sim no)
			(in_bom yes)
			(on_board yes)
			(property "Reference" "#PWR"
				(at 0 -3.81 0)
				(effects
					(font
						(size 1.27 1.27)
					)
					(hide yes)
				)
			)
			(property "Value" "+1V1"
				(at 0 3.556 0)
				(effects
					(font
						(size 1.27 1.27)
					)
				)
			)
			(property "Footprint" ""
				(at 0 0 0)
				(effects
					(font
						(size 1.27 1.27)
					)
					(hide yes)
				)
			)
			(property "Datasheet" ""
				(at 0 0 0)
				(effects
					(font
						(size 1.27 1.27)
					)
					(hide yes)
				)
			)
			(property "Description" ""
				(at 0 0 0)
				(effects
					(font
						(size 1.27 1.27)
					)
					(hide yes)
				)
			)
			(symbol "+1V1_0_1"
				(polyline
					(pts
						(xy -0.762 1.27) (xy 0 2.54)
					)
					(stroke
						(width 0)
						(type default)
					)
					(fill
						(type none)
					)
				)
				(polyline
					(pts
						(xy 0 2.54) (xy 0.762 1.27)
					)
					(stroke
						(width 0)
						(type default)
					)
					(fill
						(type none)
					)
				)
				(polyline
					(pts
						(xy 0 0) (xy 0 2.54)
					)
					(stroke
						(width 0)
						(type default)
					)
					(fill
						(type none)
					)
				)
			)
			(symbol "+1V1_1_1"
				(pin power_in line
					(at 0 0 90)
					(length 0)
					(hide yes)
					(name "+1V1"
						(effects
							(font
								(size 1.27 1.27)
							)
						)
					)
					(number "1"
						(effects
							(font
								(size 1.27 1.27)
							)
						)
					)
				)
			)
		)
	(symbol "antmicropower:+1V8"
			(power)
			(pin_numbers
				(hide yes)
			)
			(pin_names
				(hide yes)
			)
			(exclude_from_sim no)
			(in_bom yes)
			(on_board yes)
			(property "Reference" "#PWR"
				(at 15.24 -2.54 0)
				(effects
					(font
						(size 1.27 1.27)
						(thickness 0.15)
					)
					(justify left bottom)
					(hide yes)
				)
			)
			(property "Value" "+1V8"
				(at 15.24 -5.08 0)
				(effects
					(font
						(size 1.27 1.27)
						(thickness 0.15)
					)
					(justify left bottom)
				)
			)
			(property "Footprint" ""
				(at 15.24 -7.62 0)
				(effects
					(font
						(size 1.27 1.27)
						(thickness 0.15)
					)
					(justify left bottom)
					(hide yes)
				)
			)
			(property "Datasheet" ""
				(at 15.24 -10.16 0)
				(effects
					(font
						(size 1.27 1.27)
						(thickness 0.15)
					)
					(justify left bottom)
					(hide yes)
				)
			)
			(property "Description" ""
				(at 0 0 0)
				(effects
					(font
						(size 1.27 1.27)
					)
					(hide yes)
				)
			)
			(property "Author" "Antmicro"
				(at 15.24 -7.62 0)
				(effects
					(font
						(size 1.27 1.27)
						(thickness 0.15)
					)
					(justify left bottom)
					(hide yes)
				)
			)
			(property "License" "Apache-2.0"
				(at 15.24 -10.16 0)
				(effects
					(font
						(size 1.27 1.27)
						(thickness 0.15)
					)
					(justify left bottom)
					(hide yes)
				)
			)
			(symbol "+1V8_1_1"
				(polyline
					(pts
						(xy -0.762 1.27) (xy 0 2.54)
					)
					(stroke
						(width 0)
						(type default)
					)
					(fill
						(type background)
					)
				)
				(polyline
					(pts
						(xy 0 2.54) (xy 0.762 1.27)
					)
					(stroke
						(width 0)
						(type default)
					)
					(fill
						(type background)
					)
				)
				(polyline
					(pts
						(xy 0 0) (xy 0 2.54)
					)
					(stroke
						(width 0)
						(type default)
					)
					(fill
						(type background)
					)
				)
				(pin power_in line
					(at 0 0 90)
					(length 0)
					(name "+1V8"
						(effects
							(font
								(size 1.27 1.27)
							)
						)
					)
					(number "1"
						(effects
							(font
								(size 1.27 1.27)
							)
						)
					)
				)
			)
		)
	(symbol "antmicropower:+5V"
			(power)
			(pin_numbers
				(hide yes)
			)
			(pin_names
				(hide yes)
			)
			(exclude_from_sim no)
			(in_bom yes)
			(on_board yes)
			(property "Reference" "#PWR"
				(at 15.24 -2.54 0)
				(effects
					(font
						(size 1.27 1.27)
						(thickness 0.15)
					)
					(justify left bottom)
					(hide yes)
				)
			)
			(property "Value" "+5V"
				(at 15.24 -5.08 0)
				(effects
					(font
						(size 1.27 1.27)
						(thickness 0.15)
					)
					(justify left bottom)
				)
			)
			(property "Footprint" ""
				(at 15.24 -7.62 0)
				(effects
					(font
						(size 1.27 1.27)
						(thickness 0.15)
					)
					(justify left bottom)
					(hide yes)
				)
			)
			(property "Datasheet" ""
				(at 15.24 -10.16 0)
				(effects
					(font
						(size 1.27 1.27)
						(thickness 0.15)
					)
					(justify left bottom)
					(hide yes)
				)
			)
			(property "Description" ""
				(at 0 0 0)
				(effects
					(font
						(size 1.27 1.27)
					)
					(hide yes)
				)
			)
			(property "Author" "Antmicro"
				(at 15.24 -7.62 0)
				(effects
					(font
						(size 1.27 1.27)
						(thickness 0.15)
					)
					(justify left bottom)
					(hide yes)
				)
			)
			(property "License" "Apache-2.0"
				(at 15.24 -10.16 0)
				(effects
					(font
						(size 1.27 1.27)
						(thickness 0.15)
					)
					(justify left bottom)
					(hide yes)
				)
			)
			(symbol "+5V_1_1"
				(polyline
					(pts
						(xy -0.762 1.27) (xy 0 2.54)
					)
					(stroke
						(width 0)
						(type default)
					)
					(fill
						(type background)
					)
				)
				(polyline
					(pts
						(xy 0 2.54) (xy 0.762 1.27)
					)
					(stroke
						(width 0)
						(type default)
					)
					(fill
						(type background)
					)
				)
				(polyline
					(pts
						(xy 0 0) (xy 0 2.54)
					)
					(stroke
						(width 0)
						(type default)
					)
					(fill
						(type background)
					)
				)
				(pin power_in line
					(at 0 0 90)
					(length 0)
					(name "+5V"
						(effects
							(font
								(size 1.27 1.27)
							)
						)
					)
					(number "1"
						(effects
							(font
								(size 1.27 1.27)
							)
						)
					)
				)
			)
		)
	(symbol "antmicropower:GND"
			(power)
			(pin_numbers
				(hide yes)
			)
			(pin_names
				(hide yes)
			)
			(exclude_from_sim no)
			(in_bom yes)
			(on_board yes)
			(property "Reference" "#PWR"
				(at 8.89 -2.54 0)
				(effects
					(font
						(size 1.27 1.27)
						(thickness 0.15)
					)
					(justify left bottom)
					(hide yes)
				)
			)
			(property "Value" "GND"
				(at 8.89 -5.08 0)
				(effects
					(font
						(size 1.27 1.27)
						(thickness 0.15)
					)
					(justify left bottom)
				)
			)
			(property "Footprint" ""
				(at 8.89 -7.62 0)
				(effects
					(font
						(size 1.27 1.27)
						(thickness 0.15)
					)
					(justify left bottom)
					(hide yes)
				)
			)
			(property "Datasheet" ""
				(at 8.89 -12.7 0)
				(effects
					(font
						(size 1.27 1.27)
						(thickness 0.15)
					)
					(justify left bottom)
					(hide yes)
				)
			)
			(property "Description" ""
				(at 0 0 0)
				(effects
					(font
						(size 1.27 1.27)
					)
					(hide yes)
				)
			)
			(property "Author" "Antmicro"
				(at 8.89 -7.62 0)
				(effects
					(font
						(size 1.27 1.27)
						(thickness 0.15)
					)
					(justify left bottom)
					(hide yes)
				)
			)
			(property "License" "Apache-2.0"
				(at 8.89 -10.16 0)
				(effects
					(font
						(size 1.27 1.27)
						(thickness 0.15)
					)
					(justify left bottom)
					(hide yes)
				)
			)
			(symbol "GND_1_1"
				(polyline
					(pts
						(xy 0 0) (xy 0 -1.27) (xy 1.27 -1.27) (xy 0 -2.54) (xy -1.27 -1.27) (xy 0 -1.27)
					)
					(stroke
						(width 0)
						(type default)
					)
					(fill
						(type none)
					)
				)
				(pin power_in line
					(at 0 0 270)
					(length 0)
					(name "GND"
						(effects
							(font
								(size 1.27 1.27)
							)
						)
					)
					(number "1"
						(effects
							(font
								(size 1.27 1.27)
							)
						)
					)
				)
			)
		)
	(symbol "antmicropower:PWR_FLAG"
			(power)
			(pin_numbers
				(hide yes)
			)
			(pin_names
				(offset 0)
				(hide yes)
			)
			(exclude_from_sim no)
			(in_bom yes)
			(on_board yes)
			(property "Reference" "#FLG"
				(at 0 1.905 0)
				(effects
					(font
						(size 1.27 1.27)
					)
					(hide yes)
				)
			)
			(property "Value" "PWR_FLAG"
				(at 0 3.81 0)
				(effects
					(font
						(size 1.27 1.27)
					)
				)
			)
			(property "Footprint" ""
				(at 0 0 0)
				(effects
					(font
						(size 1.27 1.27)
					)
					(hide yes)
				)
			)
			(property "Datasheet" ""
				(at 0 0 0)
				(effects
					(font
						(size 1.27 1.27)
					)
					(hide yes)
				)
			)
			(property "Description" ""
				(at 0 0 0)
				(effects
					(font
						(size 1.27 1.27)
					)
					(hide yes)
				)
			)
			(symbol "PWR_FLAG_0_0"
				(pin power_out line
					(at 0 0 90)
					(length 0)
					(name "pwr"
						(effects
							(font
								(size 1.27 1.27)
							)
						)
					)
					(number "1"
						(effects
							(font
								(size 1.27 1.27)
							)
						)
					)
				)
			)
			(symbol "PWR_FLAG_0_1"
				(polyline
					(pts
						(xy 0 0) (xy 0 1.27) (xy -1.016 1.905) (xy 0 2.54) (xy 1.016 1.905) (xy 0 1.27)
					)
					(stroke
						(width 0)
						(type default)
					)
					(fill
						(type none)
					)
				)
			)
		)
	(symbol "lpddr5-testbed:Edge_Conn_Bus_DDR5_SODIMM_1xDetectPin"
			(exclude_from_sim no)
			(in_bom yes)
			(on_board yes)
			(property "Reference" "J"
				(at 52.07 0 0)
				(effects
					(font
						(size 1.27 1.27)
					)
					(justify left bottom)
				)
			)
			(property "Value" "Edge_Conn_Bus_DDR5_SODIMM_1xDetectPin"
				(at 52.07 -2.54 0)
				(effects
					(font
						(size 1.27 1.27)
					)
					(justify left bottom)
				)
			)
			(property "Footprint" "lpddr5-testbed-footprints:Edge_Conn_Bus_DDR5_SODIMM"
				(at 52.07 -12.7 0)
				(effects
					(font
						(size 1.27 1.27)
					)
					(justify left bottom)
					(hide yes)
				)
			)
			(property "Datasheet" "https://cdn.amphenol-cs.com/media/wysiwyg/files/drawing/10162416.pdf"
				(at 52.07 -10.16 0)
				(effects
					(font
						(size 1.27 1.27)
					)
					(justify left bottom)
					(hide yes)
				)
			)
			(property "Description" ""
				(at 0 0 0)
				(effects
					(font
						(size 1.27 1.27)
					)
					(hide yes)
				)
			)
			(property "MPN" ""
				(at 52.07 -7.62 0)
				(effects
					(font
						(size 1.27 1.27)
					)
					(justify left bottom)
					(hide yes)
				)
			)
			(property "Manufacturer" ""
				(at 52.07 -5.08 0)
				(effects
					(font
						(size 1.27 1.27)
					)
					(justify left bottom)
					(hide yes)
				)
			)
			(property "Author" "Antmicro"
				(at 52.07 -17.78 0)
				(effects
					(font
						(size 1.27 1.27)
					)
					(justify left bottom)
					(hide yes)
				)
			)
			(property "License" "Apache-2.0"
				(at 52.07 -15.24 0)
				(effects
					(font
						(size 1.27 1.27)
					)
					(justify left bottom)
					(hide yes)
				)
			)
			(property "ki_locked" ""
				(at 0 0 0)
				(effects
					(font
						(size 1.27 1.27)
					)
				)
			)
			(symbol "Edge_Conn_Bus_DDR5_SODIMM_1xDetectPin_0_0"
				(text ""
					(at -5.08 60.96 0)
					(effects
						(font
							(size 1.27 1.27)
						)
					)
				)
			)
			(symbol "Edge_Conn_Bus_DDR5_SODIMM_1xDetectPin_1_0"
				(pin passive line
					(at 0 0 0)
					(length 3.81)
					(name "VIN_BULK"
						(effects
							(font
								(size 1.016 1.016)
							)
						)
					)
					(number "1"
						(effects
							(font
								(size 1.016 1.016)
							)
						)
					)
				)
				(pin passive line
					(at 0 0 0)
					(length 3.81)
					(name "VIN_BULK"
						(effects
							(font
								(size 1.016 1.016)
							)
						)
					)
					(number "3"
						(effects
							(font
								(size 1.016 1.016)
							)
						)
					)
				)
				(pin input line
					(at 0 -10.16 0)
					(length 3.81)
					(name "TB_DETECT"
						(effects
							(font
								(size 1.016 1.016)
							)
						)
					)
					(number "130"
						(effects
							(font
								(size 1.016 1.016)
							)
						)
					)
				)
				(pin passive line
					(at 0 -12.7 0)
					(length 3.81)
					(name "RFU"
						(effects
							(font
								(size 1.016 1.016)
							)
						)
					)
					(number "5"
						(effects
							(font
								(size 1.016 1.016)
							)
						)
					)
				)
				(pin passive line
					(at 0 -15.24 0)
					(length 3.81)
					(name "RFU"
						(effects
							(font
								(size 1.016 1.016)
							)
						)
					)
					(number "128"
						(effects
							(font
								(size 1.016 1.016)
							)
						)
					)
				)
				(pin passive line
					(at 0 -17.78 0)
					(length 3.81)
					(name "RFU"
						(effects
							(font
								(size 1.016 1.016)
							)
						)
					)
					(number "143"
						(effects
							(font
								(size 1.016 1.016)
							)
						)
					)
				)
				(pin passive line
					(at 0 -20.32 0)
					(length 3.81)
					(name "VSS"
						(effects
							(font
								(size 1.016 1.016)
							)
						)
					)
					(number "10"
						(effects
							(font
								(size 1.016 1.016)
							)
						)
					)
				)
				(pin passive line
					(at 0 -20.32 0)
					(length 3.81)
					(hide yes)
					(name "VSS"
						(effects
							(font
								(size 1.016 1.016)
							)
						)
					)
					(number "101"
						(effects
							(font
								(size 1.016 1.016)
							)
						)
					)
				)
				(pin passive line
					(at 0 -20.32 0)
					(length 3.81)
					(hide yes)
					(name "VSS"
						(effects
							(font
								(size 1.016 1.016)
							)
						)
					)
					(number "104"
						(effects
							(font
								(size 1.016 1.016)
							)
						)
					)
				)
				(pin passive line
					(at 0 -20.32 0)
					(length 3.81)
					(hide yes)
					(name "VSS"
						(effects
							(font
								(size 1.016 1.016)
							)
						)
					)
					(number "105"
						(effects
							(font
								(size 1.016 1.016)
							)
						)
					)
				)
				(pin passive line
					(at 0 -20.32 0)
					(length 3.81)
					(hide yes)
					(name "VSS"
						(effects
							(font
								(size 1.016 1.016)
							)
						)
					)
					(number "111"
						(effects
							(font
								(size 1.016 1.016)
							)
						)
					)
				)
				(pin passive line
					(at 0 -20.32 0)
					(length 3.81)
					(hide yes)
					(name "VSS"
						(effects
							(font
								(size 1.016 1.016)
							)
						)
					)
					(number "112"
						(effects
							(font
								(size 1.016 1.016)
							)
						)
					)
				)
				(pin passive line
					(at 0 -20.32 0)
					(length 3.81)
					(hide yes)
					(name "VSS"
						(effects
							(font
								(size 1.016 1.016)
							)
						)
					)
					(number "117"
						(effects
							(font
								(size 1.016 1.016)
							)
						)
					)
				)
				(pin passive line
					(at 0 -20.32 0)
					(length 3.81)
					(hide yes)
					(name "VSS"
						(effects
							(font
								(size 1.016 1.016)
							)
						)
					)
					(number "118"
						(effects
							(font
								(size 1.016 1.016)
							)
						)
					)
				)
				(pin passive line
					(at 0 -20.32 0)
					(length 3.81)
					(hide yes)
					(name "VSS"
						(effects
							(font
								(size 1.016 1.016)
							)
						)
					)
					(number "123"
						(effects
							(font
								(size 1.016 1.016)
							)
						)
					)
				)
				(pin passive line
					(at 0 -20.32 0)
					(length 3.81)
					(hide yes)
					(name "VSS"
						(effects
							(font
								(size 1.016 1.016)
							)
						)
					)
					(number "124"
						(effects
							(font
								(size 1.016 1.016)
							)
						)
					)
				)
				(pin passive line
					(at 0 -20.32 0)
					(length 3.81)
					(hide yes)
					(name "VSS"
						(effects
							(font
								(size 1.016 1.016)
							)
						)
					)
					(number "129"
						(effects
							(font
								(size 1.016 1.016)
							)
						)
					)
				)
				(pin passive line
					(at 0 -20.32 0)
					(length 3.81)
					(hide yes)
					(name "VSS"
						(effects
							(font
								(size 1.016 1.016)
							)
						)
					)
					(number "13"
						(effects
							(font
								(size 1.016 1.016)
							)
						)
					)
				)
				(pin passive line
					(at 0 -20.32 0)
					(length 3.81)
					(hide yes)
					(name "VSS"
						(effects
							(font
								(size 1.016 1.016)
							)
						)
					)
					(number "135"
						(effects
							(font
								(size 1.016 1.016)
							)
						)
					)
				)
				(pin passive line
					(at 0 -20.32 0)
					(length 3.81)
					(hide yes)
					(name "VSS"
						(effects
							(font
								(size 1.016 1.016)
							)
						)
					)
					(number "136"
						(effects
							(font
								(size 1.016 1.016)
							)
						)
					)
				)
				(pin passive line
					(at 0 -20.32 0)
					(length 3.81)
					(hide yes)
					(name "VSS"
						(effects
							(font
								(size 1.016 1.016)
							)
						)
					)
					(number "14"
						(effects
							(font
								(size 1.016 1.016)
							)
						)
					)
				)
				(pin passive line
					(at 0 -20.32 0)
					(length 3.81)
					(hide yes)
					(name "VSS"
						(effects
							(font
								(size 1.016 1.016)
							)
						)
					)
					(number "141"
						(effects
							(font
								(size 1.016 1.016)
							)
						)
					)
				)
				(pin passive line
					(at 0 -20.32 0)
					(length 3.81)
					(hide yes)
					(name "VSS"
						(effects
							(font
								(size 1.016 1.016)
							)
						)
					)
					(number "142"
						(effects
							(font
								(size 1.016 1.016)
							)
						)
					)
				)
				(pin passive line
					(at 0 -20.32 0)
					(length 3.81)
					(hide yes)
					(name "VSS"
						(effects
							(font
								(size 1.016 1.016)
							)
						)
					)
					(number "147"
						(effects
							(font
								(size 1.016 1.016)
							)
						)
					)
				)
				(pin passive line
					(at 0 -20.32 0)
					(length 3.81)
					(hide yes)
					(name "VSS"
						(effects
							(font
								(size 1.016 1.016)
							)
						)
					)
					(number "148"
						(effects
							(font
								(size 1.016 1.016)
							)
						)
					)
				)
				(pin passive line
					(at 0 -20.32 0)
					(length 3.81)
					(hide yes)
					(name "VSS"
						(effects
							(font
								(size 1.016 1.016)
							)
						)
					)
					(number "153"
						(effects
							(font
								(size 1.016 1.016)
							)
						)
					)
				)
				(pin passive line
					(at 0 -20.32 0)
					(length 3.81)
					(hide yes)
					(name "VSS"
						(effects
							(font
								(size 1.016 1.016)
							)
						)
					)
					(number "154"
						(effects
							(font
								(size 1.016 1.016)
							)
						)
					)
				)
				(pin passive line
					(at 0 -20.32 0)
					(length 3.81)
					(hide yes)
					(name "VSS"
						(effects
							(font
								(size 1.016 1.016)
							)
						)
					)
					(number "159"
						(effects
							(font
								(size 1.016 1.016)
							)
						)
					)
				)
				(pin passive line
					(at 0 -20.32 0)
					(length 3.81)
					(hide yes)
					(name "VSS"
						(effects
							(font
								(size 1.016 1.016)
							)
						)
					)
					(number "160"
						(effects
							(font
								(size 1.016 1.016)
							)
						)
					)
				)
				(pin passive line
					(at 0 -20.32 0)
					(length 3.81)
					(hide yes)
					(name "VSS"
						(effects
							(font
								(size 1.016 1.016)
							)
						)
					)
					(number "166"
						(effects
							(font
								(size 1.016 1.016)
							)
						)
					)
				)
				(pin passive line
					(at 0 -20.32 0)
					(length 3.81)
					(hide yes)
					(name "VSS"
						(effects
							(font
								(size 1.016 1.016)
							)
						)
					)
					(number "167"
						(effects
							(font
								(size 1.016 1.016)
							)
						)
					)
				)
				(pin passive line
					(at 0 -20.32 0)
					(length 3.81)
					(hide yes)
					(name "VSS"
						(effects
							(font
								(size 1.016 1.016)
							)
						)
					)
					(number "17"
						(effects
							(font
								(size 1.016 1.016)
							)
						)
					)
				)
				(pin passive line
					(at 0 -20.32 0)
					(length 3.81)
					(hide yes)
					(name "VSS"
						(effects
							(font
								(size 1.016 1.016)
							)
						)
					)
					(number "170"
						(effects
							(font
								(size 1.016 1.016)
							)
						)
					)
				)
				(pin passive line
					(at 0 -20.32 0)
					(length 3.81)
					(hide yes)
					(name "VSS"
						(effects
							(font
								(size 1.016 1.016)
							)
						)
					)
					(number "173"
						(effects
							(font
								(size 1.016 1.016)
							)
						)
					)
				)
				(pin passive line
					(at 0 -20.32 0)
					(length 3.81)
					(hide yes)
					(name "VSS"
						(effects
							(font
								(size 1.016 1.016)
							)
						)
					)
					(number "174"
						(effects
							(font
								(size 1.016 1.016)
							)
						)
					)
				)
				(pin passive line
					(at 0 -20.32 0)
					(length 3.81)
					(hide yes)
					(name "VSS"
						(effects
							(font
								(size 1.016 1.016)
							)
						)
					)
					(number "177"
						(effects
							(font
								(size 1.016 1.016)
							)
						)
					)
				)
				(pin passive line
					(at 0 -20.32 0)
					(length 3.81)
					(hide yes)
					(name "VSS"
						(effects
							(font
								(size 1.016 1.016)
							)
						)
					)
					(number "178"
						(effects
							(font
								(size 1.016 1.016)
							)
						)
					)
				)
				(pin passive line
					(at 0 -20.32 0)
					(length 3.81)
					(hide yes)
					(name "VSS"
						(effects
							(font
								(size 1.016 1.016)
							)
						)
					)
					(number "18"
						(effects
							(font
								(size 1.016 1.016)
							)
						)
					)
				)
				(pin passive line
					(at 0 -20.32 0)
					(length 3.81)
					(hide yes)
					(name "VSS"
						(effects
							(font
								(size 1.016 1.016)
							)
						)
					)
					(number "181"
						(effects
							(font
								(size 1.016 1.016)
							)
						)
					)
				)
				(pin passive line
					(at 0 -20.32 0)
					(length 3.81)
					(hide yes)
					(name "VSS"
						(effects
							(font
								(size 1.016 1.016)
							)
						)
					)
					(number "182"
						(effects
							(font
								(size 1.016 1.016)
							)
						)
					)
				)
				(pin passive line
					(at 0 -20.32 0)
					(length 3.81)
					(hide yes)
					(name "VSS"
						(effects
							(font
								(size 1.016 1.016)
							)
						)
					)
					(number "185"
						(effects
							(font
								(size 1.016 1.016)
							)
						)
					)
				)
				(pin passive line
					(at 0 -20.32 0)
					(length 3.81)
					(hide yes)
					(name "VSS"
						(effects
							(font
								(size 1.016 1.016)
							)
						)
					)
					(number "186"
						(effects
							(font
								(size 1.016 1.016)
							)
						)
					)
				)
				(pin passive line
					(at 0 -20.32 0)
					(length 3.81)
					(hide yes)
					(name "VSS"
						(effects
							(font
								(size 1.016 1.016)
							)
						)
					)
					(number "189"
						(effects
							(font
								(size 1.016 1.016)
							)
						)
					)
				)
				(pin passive line
					(at 0 -20.32 0)
					(length 3.81)
					(hide yes)
					(name "VSS"
						(effects
							(font
								(size 1.016 1.016)
							)
						)
					)
					(number "192"
						(effects
							(font
								(size 1.016 1.016)
							)
						)
					)
				)
				(pin passive line
					(at 0 -20.32 0)
					(length 3.81)
					(hide yes)
					(name "VSS"
						(effects
							(font
								(size 1.016 1.016)
							)
						)
					)
					(number "193"
						(effects
							(font
								(size 1.016 1.016)
							)
						)
					)
				)
				(pin passive line
					(at 0 -20.32 0)
					(length 3.81)
					(hide yes)
					(name "VSS"
						(effects
							(font
								(size 1.016 1.016)
							)
						)
					)
					(number "196"
						(effects
							(font
								(size 1.016 1.016)
							)
						)
					)
				)
				(pin passive line
					(at 0 -20.32 0)
					(length 3.81)
					(hide yes)
					(name "VSS"
						(effects
							(font
								(size 1.016 1.016)
							)
						)
					)
					(number "197"
						(effects
							(font
								(size 1.016 1.016)
							)
						)
					)
				)
				(pin passive line
					(at 0 -20.32 0)
					(length 3.81)
					(hide yes)
					(name "VSS"
						(effects
							(font
								(size 1.016 1.016)
							)
						)
					)
					(number "200"
						(effects
							(font
								(size 1.016 1.016)
							)
						)
					)
				)
				(pin passive line
					(at 0 -20.32 0)
					(length 3.81)
					(hide yes)
					(name "VSS"
						(effects
							(font
								(size 1.016 1.016)
							)
						)
					)
					(number "201"
						(effects
							(font
								(size 1.016 1.016)
							)
						)
					)
				)
				(pin passive line
					(at 0 -20.32 0)
					(length 3.81)
					(hide yes)
					(name "VSS"
						(effects
							(font
								(size 1.016 1.016)
							)
						)
					)
					(number "204"
						(effects
							(font
								(size 1.016 1.016)
							)
						)
					)
				)
				(pin passive line
					(at 0 -20.32 0)
					(length 3.81)
					(hide yes)
					(name "VSS"
						(effects
							(font
								(size 1.016 1.016)
							)
						)
					)
					(number "205"
						(effects
							(font
								(size 1.016 1.016)
							)
						)
					)
				)
				(pin passive line
					(at 0 -20.32 0)
					(length 3.81)
					(hide yes)
					(name "VSS"
						(effects
							(font
								(size 1.016 1.016)
							)
						)
					)
					(number "208"
						(effects
							(font
								(size 1.016 1.016)
							)
						)
					)
				)
				(pin passive line
					(at 0 -20.32 0)
					(length 3.81)
					(hide yes)
					(name "VSS"
						(effects
							(font
								(size 1.016 1.016)
							)
						)
					)
					(number "21"
						(effects
							(font
								(size 1.016 1.016)
							)
						)
					)
				)
				(pin passive line
					(at 0 -20.32 0)
					(length 3.81)
					(hide yes)
					(name "VSS"
						(effects
							(font
								(size 1.016 1.016)
							)
						)
					)
					(number "211"
						(effects
							(font
								(size 1.016 1.016)
							)
						)
					)
				)
				(pin passive line
					(at 0 -20.32 0)
					(length 3.81)
					(hide yes)
					(name "VSS"
						(effects
							(font
								(size 1.016 1.016)
							)
						)
					)
					(number "212"
						(effects
							(font
								(size 1.016 1.016)
							)
						)
					)
				)
				(pin passive line
					(at 0 -20.32 0)
					(length 3.81)
					(hide yes)
					(name "VSS"
						(effects
							(font
								(size 1.016 1.016)
							)
						)
					)
					(number "215"
						(effects
							(font
								(size 1.016 1.016)
							)
						)
					)
				)
				(pin passive line
					(at 0 -20.32 0)
					(length 3.81)
					(hide yes)
					(name "VSS"
						(effects
							(font
								(size 1.016 1.016)
							)
						)
					)
					(number "216"
						(effects
							(font
								(size 1.016 1.016)
							)
						)
					)
				)
				(pin passive line
					(at 0 -20.32 0)
					(length 3.81)
					(hide yes)
					(name "VSS"
						(effects
							(font
								(size 1.016 1.016)
							)
						)
					)
					(number "219"
						(effects
							(font
								(size 1.016 1.016)
							)
						)
					)
				)
				(pin passive line
					(at 0 -20.32 0)
					(length 3.81)
					(hide yes)
					(name "VSS"
						(effects
							(font
								(size 1.016 1.016)
							)
						)
					)
					(number "220"
						(effects
							(font
								(size 1.016 1.016)
							)
						)
					)
				)
				(pin passive line
					(at 0 -20.32 0)
					(length 3.81)
					(hide yes)
					(name "VSS"
						(effects
							(font
								(size 1.016 1.016)
							)
						)
					)
					(number "223"
						(effects
							(font
								(size 1.016 1.016)
							)
						)
					)
				)
				(pin passive line
					(at 0 -20.32 0)
					(length 3.81)
					(hide yes)
					(name "VSS"
						(effects
							(font
								(size 1.016 1.016)
							)
						)
					)
					(number "224"
						(effects
							(font
								(size 1.016 1.016)
							)
						)
					)
				)
				(pin passive line
					(at 0 -20.32 0)
					(length 3.81)
					(hide yes)
					(name "VSS"
						(effects
							(font
								(size 1.016 1.016)
							)
						)
					)
					(number "227"
						(effects
							(font
								(size 1.016 1.016)
							)
						)
					)
				)
				(pin passive line
					(at 0 -20.32 0)
					(length 3.81)
					(hide yes)
					(name "VSS"
						(effects
							(font
								(size 1.016 1.016)
							)
						)
					)
					(number "228"
						(effects
							(font
								(size 1.016 1.016)
							)
						)
					)
				)
				(pin passive line
					(at 0 -20.32 0)
					(length 3.81)
					(hide yes)
					(name "VSS"
						(effects
							(font
								(size 1.016 1.016)
							)
						)
					)
					(number "231"
						(effects
							(font
								(size 1.016 1.016)
							)
						)
					)
				)
				(pin passive line
					(at 0 -20.32 0)
					(length 3.81)
					(hide yes)
					(name "VSS"
						(effects
							(font
								(size 1.016 1.016)
							)
						)
					)
					(number "234"
						(effects
							(font
								(size 1.016 1.016)
							)
						)
					)
				)
				(pin passive line
					(at 0 -20.32 0)
					(length 3.81)
					(hide yes)
					(name "VSS"
						(effects
							(font
								(size 1.016 1.016)
							)
						)
					)
					(number "235"
						(effects
							(font
								(size 1.016 1.016)
							)
						)
					)
				)
				(pin passive line
					(at 0 -20.32 0)
					(length 3.81)
					(hide yes)
					(name "VSS"
						(effects
							(font
								(size 1.016 1.016)
							)
						)
					)
					(number "238"
						(effects
							(font
								(size 1.016 1.016)
							)
						)
					)
				)
				(pin passive line
					(at 0 -20.32 0)
					(length 3.81)
					(hide yes)
					(name "VSS"
						(effects
							(font
								(size 1.016 1.016)
							)
						)
					)
					(number "239"
						(effects
							(font
								(size 1.016 1.016)
							)
						)
					)
				)
				(pin passive line
					(at 0 -20.32 0)
					(length 3.81)
					(hide yes)
					(name "VSS"
						(effects
							(font
								(size 1.016 1.016)
							)
						)
					)
					(number "24"
						(effects
							(font
								(size 1.016 1.016)
							)
						)
					)
				)
				(pin passive line
					(at 0 -20.32 0)
					(length 3.81)
					(hide yes)
					(name "VSS"
						(effects
							(font
								(size 1.016 1.016)
							)
						)
					)
					(number "242"
						(effects
							(font
								(size 1.016 1.016)
							)
						)
					)
				)
				(pin passive line
					(at 0 -20.32 0)
					(length 3.81)
					(hide yes)
					(name "VSS"
						(effects
							(font
								(size 1.016 1.016)
							)
						)
					)
					(number "243"
						(effects
							(font
								(size 1.016 1.016)
							)
						)
					)
				)
				(pin passive line
					(at 0 -20.32 0)
					(length 3.81)
					(hide yes)
					(name "VSS"
						(effects
							(font
								(size 1.016 1.016)
							)
						)
					)
					(number "246"
						(effects
							(font
								(size 1.016 1.016)
							)
						)
					)
				)
				(pin passive line
					(at 0 -20.32 0)
					(length 3.81)
					(hide yes)
					(name "VSS"
						(effects
							(font
								(size 1.016 1.016)
							)
						)
					)
					(number "247"
						(effects
							(font
								(size 1.016 1.016)
							)
						)
					)
				)
				(pin passive line
					(at 0 -20.32 0)
					(length 3.81)
					(hide yes)
					(name "VSS"
						(effects
							(font
								(size 1.016 1.016)
							)
						)
					)
					(number "25"
						(effects
							(font
								(size 1.016 1.016)
							)
						)
					)
				)
				(pin passive line
					(at 0 -20.32 0)
					(length 3.81)
					(hide yes)
					(name "VSS"
						(effects
							(font
								(size 1.016 1.016)
							)
						)
					)
					(number "250"
						(effects
							(font
								(size 1.016 1.016)
							)
						)
					)
				)
				(pin passive line
					(at 0 -20.32 0)
					(length 3.81)
					(hide yes)
					(name "VSS"
						(effects
							(font
								(size 1.016 1.016)
							)
						)
					)
					(number "253"
						(effects
							(font
								(size 1.016 1.016)
							)
						)
					)
				)
				(pin passive line
					(at 0 -20.32 0)
					(length 3.81)
					(hide yes)
					(name "VSS"
						(effects
							(font
								(size 1.016 1.016)
							)
						)
					)
					(number "254"
						(effects
							(font
								(size 1.016 1.016)
							)
						)
					)
				)
				(pin passive line
					(at 0 -20.32 0)
					(length 3.81)
					(hide yes)
					(name "VSS"
						(effects
							(font
								(size 1.016 1.016)
							)
						)
					)
					(number "257"
						(effects
							(font
								(size 1.016 1.016)
							)
						)
					)
				)
				(pin passive line
					(at 0 -20.32 0)
					(length 3.81)
					(hide yes)
					(name "VSS"
						(effects
							(font
								(size 1.016 1.016)
							)
						)
					)
					(number "258"
						(effects
							(font
								(size 1.016 1.016)
							)
						)
					)
				)
				(pin passive line
					(at 0 -20.32 0)
					(length 3.81)
					(hide yes)
					(name "VSS"
						(effects
							(font
								(size 1.016 1.016)
							)
						)
					)
					(number "261"
						(effects
							(font
								(size 1.016 1.016)
							)
						)
					)
				)
				(pin passive line
					(at 0 -20.32 0)
					(length 3.81)
					(hide yes)
					(name "VSS"
						(effects
							(font
								(size 1.016 1.016)
							)
						)
					)
					(number "262"
						(effects
							(font
								(size 1.016 1.016)
							)
						)
					)
				)
				(pin passive line
					(at 0 -20.32 0)
					(length 3.81)
					(hide yes)
					(name "VSS"
						(effects
							(font
								(size 1.016 1.016)
							)
						)
					)
					(number "28"
						(effects
							(font
								(size 1.016 1.016)
							)
						)
					)
				)
				(pin passive line
					(at 0 -20.32 0)
					(length 3.81)
					(hide yes)
					(name "VSS"
						(effects
							(font
								(size 1.016 1.016)
							)
						)
					)
					(number "29"
						(effects
							(font
								(size 1.016 1.016)
							)
						)
					)
				)
				(pin passive line
					(at 0 -20.32 0)
					(length 3.81)
					(hide yes)
					(name "VSS"
						(effects
							(font
								(size 1.016 1.016)
							)
						)
					)
					(number "32"
						(effects
							(font
								(size 1.016 1.016)
							)
						)
					)
				)
				(pin passive line
					(at 0 -20.32 0)
					(length 3.81)
					(hide yes)
					(name "VSS"
						(effects
							(font
								(size 1.016 1.016)
							)
						)
					)
					(number "33"
						(effects
							(font
								(size 1.016 1.016)
							)
						)
					)
				)
				(pin passive line
					(at 0 -20.32 0)
					(length 3.81)
					(hide yes)
					(name "VSS"
						(effects
							(font
								(size 1.016 1.016)
							)
						)
					)
					(number "36"
						(effects
							(font
								(size 1.016 1.016)
							)
						)
					)
				)
				(pin passive line
					(at 0 -20.32 0)
					(length 3.81)
					(hide yes)
					(name "VSS"
						(effects
							(font
								(size 1.016 1.016)
							)
						)
					)
					(number "37"
						(effects
							(font
								(size 1.016 1.016)
							)
						)
					)
				)
				(pin passive line
					(at 0 -20.32 0)
					(length 3.81)
					(hide yes)
					(name "VSS"
						(effects
							(font
								(size 1.016 1.016)
							)
						)
					)
					(number "40"
						(effects
							(font
								(size 1.016 1.016)
							)
						)
					)
				)
				(pin passive line
					(at 0 -20.32 0)
					(length 3.81)
					(hide yes)
					(name "VSS"
						(effects
							(font
								(size 1.016 1.016)
							)
						)
					)
					(number "43"
						(effects
							(font
								(size 1.016 1.016)
							)
						)
					)
				)
				(pin passive line
					(at 0 -20.32 0)
					(length 3.81)
					(hide yes)
					(name "VSS"
						(effects
							(font
								(size 1.016 1.016)
							)
						)
					)
					(number "44"
						(effects
							(font
								(size 1.016 1.016)
							)
						)
					)
				)
				(pin passive line
					(at 0 -20.32 0)
					(length 3.81)
					(hide yes)
					(name "VSS"
						(effects
							(font
								(size 1.016 1.016)
							)
						)
					)
					(number "47"
						(effects
							(font
								(size 1.016 1.016)
							)
						)
					)
				)
				(pin passive line
					(at 0 -20.32 0)
					(length 3.81)
					(hide yes)
					(name "VSS"
						(effects
							(font
								(size 1.016 1.016)
							)
						)
					)
					(number "48"
						(effects
							(font
								(size 1.016 1.016)
							)
						)
					)
				)
				(pin passive line
					(at 0 -20.32 0)
					(length 3.81)
					(hide yes)
					(name "VSS"
						(effects
							(font
								(size 1.016 1.016)
							)
						)
					)
					(number "51"
						(effects
							(font
								(size 1.016 1.016)
							)
						)
					)
				)
				(pin passive line
					(at 0 -20.32 0)
					(length 3.81)
					(hide yes)
					(name "VSS"
						(effects
							(font
								(size 1.016 1.016)
							)
						)
					)
					(number "52"
						(effects
							(font
								(size 1.016 1.016)
							)
						)
					)
				)
				(pin passive line
					(at 0 -20.32 0)
					(length 3.81)
					(hide yes)
					(name "VSS"
						(effects
							(font
								(size 1.016 1.016)
							)
						)
					)
					(number "55"
						(effects
							(font
								(size 1.016 1.016)
							)
						)
					)
				)
				(pin passive line
					(at 0 -20.32 0)
					(length 3.81)
					(hide yes)
					(name "VSS"
						(effects
							(font
								(size 1.016 1.016)
							)
						)
					)
					(number "56"
						(effects
							(font
								(size 1.016 1.016)
							)
						)
					)
				)
				(pin passive line
					(at 0 -20.32 0)
					(length 3.81)
					(hide yes)
					(name "VSS"
						(effects
							(font
								(size 1.016 1.016)
							)
						)
					)
					(number "59"
						(effects
							(font
								(size 1.016 1.016)
							)
						)
					)
				)
				(pin passive line
					(at 0 -20.32 0)
					(length 3.81)
					(hide yes)
					(name "VSS"
						(effects
							(font
								(size 1.016 1.016)
							)
						)
					)
					(number "60"
						(effects
							(font
								(size 1.016 1.016)
							)
						)
					)
				)
				(pin passive line
					(at 0 -20.32 0)
					(length 3.81)
					(hide yes)
					(name "VSS"
						(effects
							(font
								(size 1.016 1.016)
							)
						)
					)
					(number "63"
						(effects
							(font
								(size 1.016 1.016)
							)
						)
					)
				)
				(pin passive line
					(at 0 -20.32 0)
					(length 3.81)
					(hide yes)
					(name "VSS"
						(effects
							(font
								(size 1.016 1.016)
							)
						)
					)
					(number "66"
						(effects
							(font
								(size 1.016 1.016)
							)
						)
					)
				)
				(pin passive line
					(at 0 -20.32 0)
					(length 3.81)
					(hide yes)
					(name "VSS"
						(effects
							(font
								(size 1.016 1.016)
							)
						)
					)
					(number "67"
						(effects
							(font
								(size 1.016 1.016)
							)
						)
					)
				)
				(pin passive line
					(at 0 -20.32 0)
					(length 3.81)
					(hide yes)
					(name "VSS"
						(effects
							(font
								(size 1.016 1.016)
							)
						)
					)
					(number "70"
						(effects
							(font
								(size 1.016 1.016)
							)
						)
					)
				)
				(pin passive line
					(at 0 -20.32 0)
					(length 3.81)
					(hide yes)
					(name "VSS"
						(effects
							(font
								(size 1.016 1.016)
							)
						)
					)
					(number "71"
						(effects
							(font
								(size 1.016 1.016)
							)
						)
					)
				)
				(pin passive line
					(at 0 -20.32 0)
					(length 3.81)
					(hide yes)
					(name "VSS"
						(effects
							(font
								(size 1.016 1.016)
							)
						)
					)
					(number "74"
						(effects
							(font
								(size 1.016 1.016)
							)
						)
					)
				)
				(pin passive line
					(at 0 -20.32 0)
					(length 3.81)
					(hide yes)
					(name "VSS"
						(effects
							(font
								(size 1.016 1.016)
							)
						)
					)
					(number "75"
						(effects
							(font
								(size 1.016 1.016)
							)
						)
					)
				)
				(pin passive line
					(at 0 -20.32 0)
					(length 3.81)
					(hide yes)
					(name "VSS"
						(effects
							(font
								(size 1.016 1.016)
							)
						)
					)
					(number "78"
						(effects
							(font
								(size 1.016 1.016)
							)
						)
					)
				)
				(pin passive line
					(at 0 -20.32 0)
					(length 3.81)
					(hide yes)
					(name "VSS"
						(effects
							(font
								(size 1.016 1.016)
							)
						)
					)
					(number "79"
						(effects
							(font
								(size 1.016 1.016)
							)
						)
					)
				)
				(pin passive line
					(at 0 -20.32 0)
					(length 3.81)
					(hide yes)
					(name "VSS"
						(effects
							(font
								(size 1.016 1.016)
							)
						)
					)
					(number "82"
						(effects
							(font
								(size 1.016 1.016)
							)
						)
					)
				)
				(pin passive line
					(at 0 -20.32 0)
					(length 3.81)
					(hide yes)
					(name "VSS"
						(effects
							(font
								(size 1.016 1.016)
							)
						)
					)
					(number "85"
						(effects
							(font
								(size 1.016 1.016)
							)
						)
					)
				)
				(pin passive line
					(at 0 -20.32 0)
					(length 3.81)
					(hide yes)
					(name "VSS"
						(effects
							(font
								(size 1.016 1.016)
							)
						)
					)
					(number "86"
						(effects
							(font
								(size 1.016 1.016)
							)
						)
					)
				)
				(pin passive line
					(at 0 -20.32 0)
					(length 3.81)
					(hide yes)
					(name "VSS"
						(effects
							(font
								(size 1.016 1.016)
							)
						)
					)
					(number "89"
						(effects
							(font
								(size 1.016 1.016)
							)
						)
					)
				)
				(pin passive line
					(at 0 -20.32 0)
					(length 3.81)
					(hide yes)
					(name "VSS"
						(effects
							(font
								(size 1.016 1.016)
							)
						)
					)
					(number "9"
						(effects
							(font
								(size 1.016 1.016)
							)
						)
					)
				)
				(pin passive line
					(at 0 -20.32 0)
					(length 3.81)
					(hide yes)
					(name "VSS"
						(effects
							(font
								(size 1.016 1.016)
							)
						)
					)
					(number "90"
						(effects
							(font
								(size 1.016 1.016)
							)
						)
					)
				)
				(pin passive line
					(at 0 -20.32 0)
					(length 3.81)
					(hide yes)
					(name "VSS"
						(effects
							(font
								(size 1.016 1.016)
							)
						)
					)
					(number "93"
						(effects
							(font
								(size 1.016 1.016)
							)
						)
					)
				)
				(pin passive line
					(at 0 -20.32 0)
					(length 3.81)
					(hide yes)
					(name "VSS"
						(effects
							(font
								(size 1.016 1.016)
							)
						)
					)
					(number "94"
						(effects
							(font
								(size 1.016 1.016)
							)
						)
					)
				)
				(pin passive line
					(at 0 -20.32 0)
					(length 3.81)
					(hide yes)
					(name "VSS"
						(effects
							(font
								(size 1.016 1.016)
							)
						)
					)
					(number "97"
						(effects
							(font
								(size 1.016 1.016)
							)
						)
					)
				)
				(pin passive line
					(at 0 -20.32 0)
					(length 3.81)
					(hide yes)
					(name "VSS"
						(effects
							(font
								(size 1.016 1.016)
							)
						)
					)
					(number "98"
						(effects
							(font
								(size 1.016 1.016)
							)
						)
					)
				)
				(pin passive line
					(at 25.4 0 180)
					(length 3.81)
					(name "PWR_EN"
						(effects
							(font
								(size 1.016 1.016)
							)
						)
					)
					(number "8"
						(effects
							(font
								(size 1.016 1.016)
							)
						)
					)
				)
				(pin passive line
					(at 25.4 -2.54 180)
					(length 3.81)
					(name "RESET_n"
						(effects
							(font
								(size 1.016 1.016)
							)
						)
					)
					(number "163"
						(effects
							(font
								(size 1.016 1.016)
							)
						)
					)
				)
				(pin passive line
					(at 25.4 -7.62 180)
					(length 3.81)
					(name "HSA"
						(effects
							(font
								(size 1.016 1.016)
							)
						)
					)
					(number "2"
						(effects
							(font
								(size 1.016 1.016)
							)
						)
					)
				)
				(pin passive line
					(at 25.4 -10.16 180)
					(length 3.81)
					(name "HSCL"
						(effects
							(font
								(size 1.016 1.016)
							)
						)
					)
					(number "4"
						(effects
							(font
								(size 1.016 1.016)
							)
						)
					)
				)
				(pin passive line
					(at 25.4 -12.7 180)
					(length 3.81)
					(name "HSDA"
						(effects
							(font
								(size 1.016 1.016)
							)
						)
					)
					(number "6"
						(effects
							(font
								(size 1.016 1.016)
							)
						)
					)
				)
				(pin passive line
					(at 25.4 -17.78 180)
					(length 3.81)
					(name "PWR_GOOD"
						(effects
							(font
								(size 1.016 1.016)
							)
						)
					)
					(number "7"
						(effects
							(font
								(size 1.016 1.016)
							)
						)
					)
				)
				(pin passive line
					(at 25.4 -20.32 180)
					(length 3.81)
					(name "ALERT_n"
						(effects
							(font
								(size 1.016 1.016)
							)
						)
					)
					(number "108"
						(effects
							(font
								(size 1.016 1.016)
							)
						)
					)
				)
			)
			(symbol "Edge_Conn_Bus_DDR5_SODIMM_1xDetectPin_1_1"
				(rectangle
					(start 3.81 2.54)
					(end 21.59 -22.86)
					(stroke
						(width 0)
						(type default)
					)
					(fill
						(type background)
					)
				)
			)
			(symbol "Edge_Conn_Bus_DDR5_SODIMM_1xDetectPin_2_0"
				(pin passive line
					(at 0 0 0)
					(length 3.81)
					(name "CS0_A_n"
						(effects
							(font
								(size 1.016 1.016)
							)
						)
					)
					(number "106"
						(effects
							(font
								(size 1.016 1.016)
							)
						)
					)
				)
				(pin passive line
					(at 0 -2.54 0)
					(length 3.81)
					(name "CS1_A_n"
						(effects
							(font
								(size 1.016 1.016)
							)
						)
					)
					(number "110"
						(effects
							(font
								(size 1.016 1.016)
							)
						)
					)
				)
				(pin passive line
					(at 0 -10.16 0)
					(length 3.81)
					(name "DM0_A_n"
						(effects
							(font
								(size 1.016 1.016)
							)
						)
					)
					(number "19"
						(effects
							(font
								(size 1.016 1.016)
							)
						)
					)
				)
				(pin passive line
					(at 0 -12.7 0)
					(length 3.81)
					(name "DM1_A_n"
						(effects
							(font
								(size 1.016 1.016)
							)
						)
					)
					(number "42"
						(effects
							(font
								(size 1.016 1.016)
							)
						)
					)
				)
				(pin passive line
					(at 0 -15.24 0)
					(length 3.81)
					(name "DM2_A_n"
						(effects
							(font
								(size 1.016 1.016)
							)
						)
					)
					(number "61"
						(effects
							(font
								(size 1.016 1.016)
							)
						)
					)
				)
				(pin passive line
					(at 0 -17.78 0)
					(length 3.81)
					(name "DM3_A_n"
						(effects
							(font
								(size 1.016 1.016)
							)
						)
					)
					(number "84"
						(effects
							(font
								(size 1.016 1.016)
							)
						)
					)
				)
				(pin passive line
					(at 0 -25.4 0)
					(length 3.81)
					(name "CK0_A_t"
						(effects
							(font
								(size 1.016 1.016)
							)
						)
					)
					(number "131"
						(effects
							(font
								(size 1.016 1.016)
							)
						)
					)
				)
				(pin passive line
					(at 0 -27.94 0)
					(length 3.81)
					(name "CK0_A_c"
						(effects
							(font
								(size 1.016 1.016)
							)
						)
					)
					(number "133"
						(effects
							(font
								(size 1.016 1.016)
							)
						)
					)
				)
				(pin passive line
					(at 0 -33.02 0)
					(length 3.81)
					(name "CK1_A_t"
						(effects
							(font
								(size 1.016 1.016)
							)
						)
					)
					(number "132"
						(effects
							(font
								(size 1.016 1.016)
							)
						)
					)
				)
				(pin passive line
					(at 0 -35.56 0)
					(length 3.81)
					(name "CK1_A_c"
						(effects
							(font
								(size 1.016 1.016)
							)
						)
					)
					(number "134"
						(effects
							(font
								(size 1.016 1.016)
							)
						)
					)
				)
				(pin passive line
					(at 0 -40.64 0)
					(length 3.81)
					(name "CA0_A"
						(effects
							(font
								(size 1.016 1.016)
							)
						)
					)
					(number "107"
						(effects
							(font
								(size 1.016 1.016)
							)
						)
					)
				)
				(pin passive line
					(at 0 -43.18 0)
					(length 3.81)
					(name "CA1_A"
						(effects
							(font
								(size 1.016 1.016)
							)
						)
					)
					(number "109"
						(effects
							(font
								(size 1.016 1.016)
							)
						)
					)
				)
				(pin passive line
					(at 0 -45.72 0)
					(length 3.81)
					(name "CA2_A"
						(effects
							(font
								(size 1.016 1.016)
							)
						)
					)
					(number "113"
						(effects
							(font
								(size 1.016 1.016)
							)
						)
					)
				)
				(pin passive line
					(at 0 -48.26 0)
					(length 3.81)
					(name "CA3_A"
						(effects
							(font
								(size 1.016 1.016)
							)
						)
					)
					(number "114"
						(effects
							(font
								(size 1.016 1.016)
							)
						)
					)
				)
				(pin passive line
					(at 0 -50.8 0)
					(length 3.81)
					(name "CA4_A"
						(effects
							(font
								(size 1.016 1.016)
							)
						)
					)
					(number "115"
						(effects
							(font
								(size 1.016 1.016)
							)
						)
					)
				)
				(pin passive line
					(at 0 -53.34 0)
					(length 3.81)
					(name "CA5_A"
						(effects
							(font
								(size 1.016 1.016)
							)
						)
					)
					(number "116"
						(effects
							(font
								(size 1.016 1.016)
							)
						)
					)
				)
				(pin passive line
					(at 0 -55.88 0)
					(length 3.81)
					(name "CA6_A"
						(effects
							(font
								(size 1.016 1.016)
							)
						)
					)
					(number "119"
						(effects
							(font
								(size 1.016 1.016)
							)
						)
					)
				)
				(pin passive line
					(at 0 -58.42 0)
					(length 3.81)
					(name "CA7_A"
						(effects
							(font
								(size 1.016 1.016)
							)
						)
					)
					(number "120"
						(effects
							(font
								(size 1.016 1.016)
							)
						)
					)
				)
				(pin passive line
					(at 0 -60.96 0)
					(length 3.81)
					(name "CA8_A"
						(effects
							(font
								(size 1.016 1.016)
							)
						)
					)
					(number "121"
						(effects
							(font
								(size 1.016 1.016)
							)
						)
					)
				)
				(pin passive line
					(at 0 -63.5 0)
					(length 3.81)
					(name "CA9_A"
						(effects
							(font
								(size 1.016 1.016)
							)
						)
					)
					(number "122"
						(effects
							(font
								(size 1.016 1.016)
							)
						)
					)
				)
				(pin passive line
					(at 0 -66.04 0)
					(length 3.81)
					(name "CA10_A"
						(effects
							(font
								(size 1.016 1.016)
							)
						)
					)
					(number "125"
						(effects
							(font
								(size 1.016 1.016)
							)
						)
					)
				)
				(pin passive line
					(at 0 -68.58 0)
					(length 3.81)
					(name "CA11_A"
						(effects
							(font
								(size 1.016 1.016)
							)
						)
					)
					(number "126"
						(effects
							(font
								(size 1.016 1.016)
							)
						)
					)
				)
				(pin passive line
					(at 0 -71.12 0)
					(length 3.81)
					(name "CA12_A"
						(effects
							(font
								(size 1.016 1.016)
							)
						)
					)
					(number "127"
						(effects
							(font
								(size 1.016 1.016)
							)
						)
					)
				)
				(pin passive line
					(at 0 -78.74 0)
					(length 3.81)
					(name "DQS4_A_t"
						(effects
							(font
								(size 1.016 1.016)
							)
						)
					)
					(number "102"
						(effects
							(font
								(size 1.016 1.016)
							)
						)
					)
				)
				(pin passive line
					(at 0 -81.28 0)
					(length 3.81)
					(name "DQS4_A_c"
						(effects
							(font
								(size 1.016 1.016)
							)
						)
					)
					(number "100"
						(effects
							(font
								(size 1.016 1.016)
							)
						)
					)
				)
				(pin passive line
					(at 0 -86.36 0)
					(length 3.81)
					(name "CB0_A"
						(effects
							(font
								(size 1.016 1.016)
							)
						)
					)
					(number "95"
						(effects
							(font
								(size 1.016 1.016)
							)
						)
					)
				)
				(pin passive line
					(at 0 -88.9 0)
					(length 3.81)
					(name "CB1_A"
						(effects
							(font
								(size 1.016 1.016)
							)
						)
					)
					(number "96"
						(effects
							(font
								(size 1.016 1.016)
							)
						)
					)
				)
				(pin passive line
					(at 0 -91.44 0)
					(length 3.81)
					(name "CB2_A"
						(effects
							(font
								(size 1.016 1.016)
							)
						)
					)
					(number "99"
						(effects
							(font
								(size 1.016 1.016)
							)
						)
					)
				)
				(pin passive line
					(at 0 -93.98 0)
					(length 3.81)
					(name "CB3_A"
						(effects
							(font
								(size 1.016 1.016)
							)
						)
					)
					(number "103"
						(effects
							(font
								(size 1.016 1.016)
							)
						)
					)
				)
				(pin passive line
					(at 35.56 0 180)
					(length 3.81)
					(name "DQS0_A_t"
						(effects
							(font
								(size 1.016 1.016)
							)
						)
					)
					(number "22"
						(effects
							(font
								(size 1.016 1.016)
							)
						)
					)
				)
				(pin passive line
					(at 35.56 -2.54 180)
					(length 3.81)
					(name "DQS0_A_C"
						(effects
							(font
								(size 1.016 1.016)
							)
						)
					)
					(number "20"
						(effects
							(font
								(size 1.016 1.016)
							)
						)
					)
				)
				(pin passive line
					(at 35.56 -7.62 180)
					(length 3.81)
					(name "DQ0_A"
						(effects
							(font
								(size 1.016 1.016)
							)
						)
					)
					(number "11"
						(effects
							(font
								(size 1.016 1.016)
							)
						)
					)
				)
				(pin passive line
					(at 35.56 -10.16 180)
					(length 3.81)
					(name "DQ1_A"
						(effects
							(font
								(size 1.016 1.016)
							)
						)
					)
					(number "12"
						(effects
							(font
								(size 1.016 1.016)
							)
						)
					)
				)
				(pin passive line
					(at 35.56 -12.7 180)
					(length 3.81)
					(name "DQ2_A"
						(effects
							(font
								(size 1.016 1.016)
							)
						)
					)
					(number "15"
						(effects
							(font
								(size 1.016 1.016)
							)
						)
					)
				)
				(pin passive line
					(at 35.56 -15.24 180)
					(length 3.81)
					(name "DQ3_A"
						(effects
							(font
								(size 1.016 1.016)
							)
						)
					)
					(number "16"
						(effects
							(font
								(size 1.016 1.016)
							)
						)
					)
				)
				(pin passive line
					(at 35.56 -17.78 180)
					(length 3.81)
					(name "DQ4_A"
						(effects
							(font
								(size 1.016 1.016)
							)
						)
					)
					(number "23"
						(effects
							(font
								(size 1.016 1.016)
							)
						)
					)
				)
				(pin passive line
					(at 35.56 -20.32 180)
					(length 3.81)
					(name "DQ5_A"
						(effects
							(font
								(size 1.016 1.016)
							)
						)
					)
					(number "26"
						(effects
							(font
								(size 1.016 1.016)
							)
						)
					)
				)
				(pin passive line
					(at 35.56 -22.86 180)
					(length 3.81)
					(name "DQ6_A"
						(effects
							(font
								(size 1.016 1.016)
							)
						)
					)
					(number "27"
						(effects
							(font
								(size 1.016 1.016)
							)
						)
					)
				)
				(pin passive line
					(at 35.56 -25.4 180)
					(length 3.81)
					(name "DQ7_A"
						(effects
							(font
								(size 1.016 1.016)
							)
						)
					)
					(number "30"
						(effects
							(font
								(size 1.016 1.016)
							)
						)
					)
				)
				(pin passive line
					(at 35.56 -30.48 180)
					(length 3.81)
					(name "DQS1_A_t"
						(effects
							(font
								(size 1.016 1.016)
							)
						)
					)
					(number "41"
						(effects
							(font
								(size 1.016 1.016)
							)
						)
					)
				)
				(pin passive line
					(at 35.56 -33.02 180)
					(length 3.81)
					(name "DQS1_A_C"
						(effects
							(font
								(size 1.016 1.016)
							)
						)
					)
					(number "39"
						(effects
							(font
								(size 1.016 1.016)
							)
						)
					)
				)
				(pin passive line
					(at 35.56 -38.1 180)
					(length 3.81)
					(name "DQ8_A"
						(effects
							(font
								(size 1.016 1.016)
							)
						)
					)
					(number "31"
						(effects
							(font
								(size 1.016 1.016)
							)
						)
					)
				)
				(pin passive line
					(at 35.56 -40.64 180)
					(length 3.81)
					(name "DQ09_A"
						(effects
							(font
								(size 1.016 1.016)
							)
						)
					)
					(number "34"
						(effects
							(font
								(size 1.016 1.016)
							)
						)
					)
				)
				(pin passive line
					(at 35.56 -43.18 180)
					(length 3.81)
					(name "DQ10_A"
						(effects
							(font
								(size 1.016 1.016)
							)
						)
					)
					(number "35"
						(effects
							(font
								(size 1.016 1.016)
							)
						)
					)
				)
				(pin passive line
					(at 35.56 -45.72 180)
					(length 3.81)
					(name "DQ11_A"
						(effects
							(font
								(size 1.016 1.016)
							)
						)
					)
					(number "38"
						(effects
							(font
								(size 1.016 1.016)
							)
						)
					)
				)
				(pin passive line
					(at 35.56 -48.26 180)
					(length 3.81)
					(name "DQ12_A"
						(effects
							(font
								(size 1.016 1.016)
							)
						)
					)
					(number "45"
						(effects
							(font
								(size 1.016 1.016)
							)
						)
					)
				)
				(pin passive line
					(at 35.56 -50.8 180)
					(length 3.81)
					(name "DQ13_A"
						(effects
							(font
								(size 1.016 1.016)
							)
						)
					)
					(number "46"
						(effects
							(font
								(size 1.016 1.016)
							)
						)
					)
				)
				(pin passive line
					(at 35.56 -53.34 180)
					(length 3.81)
					(name "DQ14_A"
						(effects
							(font
								(size 1.016 1.016)
							)
						)
					)
					(number "49"
						(effects
							(font
								(size 1.016 1.016)
							)
						)
					)
				)
				(pin passive line
					(at 35.56 -55.88 180)
					(length 3.81)
					(name "DQ15_A"
						(effects
							(font
								(size 1.016 1.016)
							)
						)
					)
					(number "50"
						(effects
							(font
								(size 1.016 1.016)
							)
						)
					)
				)
				(pin passive line
					(at 35.56 -60.96 180)
					(length 3.81)
					(name "DQS2_A_t"
						(effects
							(font
								(size 1.016 1.016)
							)
						)
					)
					(number "64"
						(effects
							(font
								(size 1.016 1.016)
							)
						)
					)
				)
				(pin passive line
					(at 35.56 -63.5 180)
					(length 3.81)
					(name "DQS2_A_C"
						(effects
							(font
								(size 1.016 1.016)
							)
						)
					)
					(number "62"
						(effects
							(font
								(size 1.016 1.016)
							)
						)
					)
				)
				(pin passive line
					(at 35.56 -68.58 180)
					(length 3.81)
					(name "DQ16_A"
						(effects
							(font
								(size 1.016 1.016)
							)
						)
					)
					(number "53"
						(effects
							(font
								(size 1.016 1.016)
							)
						)
					)
				)
				(pin passive line
					(at 35.56 -71.12 180)
					(length 3.81)
					(name "DQ17_A"
						(effects
							(font
								(size 1.016 1.016)
							)
						)
					)
					(number "54"
						(effects
							(font
								(size 1.016 1.016)
							)
						)
					)
				)
				(pin passive line
					(at 35.56 -73.66 180)
					(length 3.81)
					(name "DQ18_A"
						(effects
							(font
								(size 1.016 1.016)
							)
						)
					)
					(number "57"
						(effects
							(font
								(size 1.016 1.016)
							)
						)
					)
				)
				(pin passive line
					(at 35.56 -76.2 180)
					(length 3.81)
					(name "DQ19_A"
						(effects
							(font
								(size 1.016 1.016)
							)
						)
					)
					(number "58"
						(effects
							(font
								(size 1.016 1.016)
							)
						)
					)
				)
				(pin passive line
					(at 35.56 -78.74 180)
					(length 3.81)
					(name "DQ20_A"
						(effects
							(font
								(size 1.016 1.016)
							)
						)
					)
					(number "65"
						(effects
							(font
								(size 1.016 1.016)
							)
						)
					)
				)
				(pin passive line
					(at 35.56 -81.28 180)
					(length 3.81)
					(name "DQ21_A"
						(effects
							(font
								(size 1.016 1.016)
							)
						)
					)
					(number "68"
						(effects
							(font
								(size 1.016 1.016)
							)
						)
					)
				)
				(pin passive line
					(at 35.56 -83.82 180)
					(length 3.81)
					(name "DQ22_A"
						(effects
							(font
								(size 1.016 1.016)
							)
						)
					)
					(number "69"
						(effects
							(font
								(size 1.016 1.016)
							)
						)
					)
				)
				(pin passive line
					(at 35.56 -86.36 180)
					(length 3.81)
					(name "DQ23_A"
						(effects
							(font
								(size 1.016 1.016)
							)
						)
					)
					(number "72"
						(effects
							(font
								(size 1.016 1.016)
							)
						)
					)
				)
				(pin passive line
					(at 35.56 -91.44 180)
					(length 3.81)
					(name "DQS3_A_t"
						(effects
							(font
								(size 1.016 1.016)
							)
						)
					)
					(number "83"
						(effects
							(font
								(size 1.016 1.016)
							)
						)
					)
				)
				(pin passive line
					(at 35.56 -93.98 180)
					(length 3.81)
					(name "DQS3_A_C"
						(effects
							(font
								(size 1.016 1.016)
							)
						)
					)
					(number "81"
						(effects
							(font
								(size 1.016 1.016)
							)
						)
					)
				)
				(pin passive line
					(at 35.56 -99.06 180)
					(length 3.81)
					(name "DQ24_A"
						(effects
							(font
								(size 1.016 1.016)
							)
						)
					)
					(number "73"
						(effects
							(font
								(size 1.016 1.016)
							)
						)
					)
				)
				(pin passive line
					(at 35.56 -101.6 180)
					(length 3.81)
					(name "DQ25_A"
						(effects
							(font
								(size 1.016 1.016)
							)
						)
					)
					(number "76"
						(effects
							(font
								(size 1.016 1.016)
							)
						)
					)
				)
				(pin passive line
					(at 35.56 -104.14 180)
					(length 3.81)
					(name "DQ26_A"
						(effects
							(font
								(size 1.016 1.016)
							)
						)
					)
					(number "77"
						(effects
							(font
								(size 1.016 1.016)
							)
						)
					)
				)
				(pin passive line
					(at 35.56 -106.68 180)
					(length 3.81)
					(name "DQ27_A"
						(effects
							(font
								(size 1.016 1.016)
							)
						)
					)
					(number "80"
						(effects
							(font
								(size 1.016 1.016)
							)
						)
					)
				)
				(pin passive line
					(at 35.56 -109.22 180)
					(length 3.81)
					(name "DQ28_A"
						(effects
							(font
								(size 1.016 1.016)
							)
						)
					)
					(number "87"
						(effects
							(font
								(size 1.016 1.016)
							)
						)
					)
				)
				(pin passive line
					(at 35.56 -111.76 180)
					(length 3.81)
					(name "DQ29_A"
						(effects
							(font
								(size 1.016 1.016)
							)
						)
					)
					(number "88"
						(effects
							(font
								(size 1.016 1.016)
							)
						)
					)
				)
				(pin passive line
					(at 35.56 -114.3 180)
					(length 3.81)
					(name "DQ30_A"
						(effects
							(font
								(size 1.016 1.016)
							)
						)
					)
					(number "91"
						(effects
							(font
								(size 1.016 1.016)
							)
						)
					)
				)
				(pin passive line
					(at 35.56 -116.84 180)
					(length 3.81)
					(name "DQ31_A"
						(effects
							(font
								(size 1.016 1.016)
							)
						)
					)
					(number "92"
						(effects
							(font
								(size 1.016 1.016)
							)
						)
					)
				)
			)
			(symbol "Edge_Conn_Bus_DDR5_SODIMM_1xDetectPin_2_1"
				(rectangle
					(start 3.81 2.54)
					(end 31.75 -119.38)
					(stroke
						(width 0)
						(type default)
					)
					(fill
						(type background)
					)
				)
				(polyline
					(pts
						(xy 10.16 -76.2) (xy 13.97 -76.2) (xy 13.97 -96.52) (xy 10.16 -96.52)
					)
					(stroke
						(width 0)
						(type default)
					)
					(fill
						(type none)
					)
				)
				(polyline
					(pts
						(xy 22.86 0) (xy 22.86 -25.4)
					)
					(stroke
						(width 0)
						(type default)
					)
					(fill
						(type none)
					)
				)
				(polyline
					(pts
						(xy 22.86 -30.48) (xy 22.86 -55.88)
					)
					(stroke
						(width 0)
						(type default)
					)
					(fill
						(type none)
					)
				)
				(polyline
					(pts
						(xy 22.86 -60.96) (xy 22.86 -86.36)
					)
					(stroke
						(width 0)
						(type default)
					)
					(fill
						(type none)
					)
				)
				(polyline
					(pts
						(xy 22.86 -91.44) (xy 22.86 -116.84)
					)
					(stroke
						(width 0)
						(type default)
					)
					(fill
						(type none)
					)
				)
				(text "ECC"
					(at 12.7 -86.36 900)
					(effects
						(font
							(size 1.27 1.27)
						)
					)
				)
			)
			(symbol "Edge_Conn_Bus_DDR5_SODIMM_1xDetectPin_3_0"
				(pin passive line
					(at 0 0 0)
					(length 3.81)
					(name "CS0_B_n"
						(effects
							(font
								(size 1.016 1.016)
							)
						)
					)
					(number "161"
						(effects
							(font
								(size 1.016 1.016)
							)
						)
					)
				)
				(pin passive line
					(at 0 -2.54 0)
					(length 3.81)
					(name "CS1_B_N"
						(effects
							(font
								(size 1.016 1.016)
							)
						)
					)
					(number "165"
						(effects
							(font
								(size 1.016 1.016)
							)
						)
					)
				)
				(pin passive line
					(at 0 -10.16 0)
					(length 3.81)
					(name "DM0_B_n"
						(effects
							(font
								(size 1.016 1.016)
							)
						)
					)
					(number "187"
						(effects
							(font
								(size 1.016 1.016)
							)
						)
					)
				)
				(pin passive line
					(at 0 -12.7 0)
					(length 3.81)
					(name "DM1_B_n"
						(effects
							(font
								(size 1.016 1.016)
							)
						)
					)
					(number "210"
						(effects
							(font
								(size 1.016 1.016)
							)
						)
					)
				)
				(pin passive line
					(at 0 -15.24 0)
					(length 3.81)
					(name "DM2_B_n"
						(effects
							(font
								(size 1.016 1.016)
							)
						)
					)
					(number "229"
						(effects
							(font
								(size 1.016 1.016)
							)
						)
					)
				)
				(pin passive line
					(at 0 -17.78 0)
					(length 3.81)
					(name "DM3_B_n"
						(effects
							(font
								(size 1.016 1.016)
							)
						)
					)
					(number "252"
						(effects
							(font
								(size 1.016 1.016)
							)
						)
					)
				)
				(pin passive line
					(at 0 -25.4 0)
					(length 3.81)
					(name "CK0_B_t"
						(effects
							(font
								(size 1.016 1.016)
							)
						)
					)
					(number "137"
						(effects
							(font
								(size 1.016 1.016)
							)
						)
					)
				)
				(pin passive line
					(at 0 -27.94 0)
					(length 3.81)
					(name "CK0_B_c"
						(effects
							(font
								(size 1.016 1.016)
							)
						)
					)
					(number "139"
						(effects
							(font
								(size 1.016 1.016)
							)
						)
					)
				)
				(pin passive line
					(at 0 -33.02 0)
					(length 3.81)
					(name "CK1_B_t"
						(effects
							(font
								(size 1.016 1.016)
							)
						)
					)
					(number "138"
						(effects
							(font
								(size 1.016 1.016)
							)
						)
					)
				)
				(pin passive line
					(at 0 -35.56 0)
					(length 3.81)
					(name "CK1_B_C"
						(effects
							(font
								(size 1.016 1.016)
							)
						)
					)
					(number "140"
						(effects
							(font
								(size 1.016 1.016)
							)
						)
					)
				)
				(pin passive line
					(at 0 -40.64 0)
					(length 3.81)
					(name "CA0_B"
						(effects
							(font
								(size 1.016 1.016)
							)
						)
					)
					(number "164"
						(effects
							(font
								(size 1.016 1.016)
							)
						)
					)
				)
				(pin passive line
					(at 0 -43.18 0)
					(length 3.81)
					(name "CA1_B"
						(effects
							(font
								(size 1.016 1.016)
							)
						)
					)
					(number "162"
						(effects
							(font
								(size 1.016 1.016)
							)
						)
					)
				)
				(pin passive line
					(at 0 -45.72 0)
					(length 3.81)
					(name "CA2_B"
						(effects
							(font
								(size 1.016 1.016)
							)
						)
					)
					(number "158"
						(effects
							(font
								(size 1.016 1.016)
							)
						)
					)
				)
				(pin passive line
					(at 0 -48.26 0)
					(length 3.81)
					(name "CA3_B"
						(effects
							(font
								(size 1.016 1.016)
							)
						)
					)
					(number "157"
						(effects
							(font
								(size 1.016 1.016)
							)
						)
					)
				)
				(pin passive line
					(at 0 -50.8 0)
					(length 3.81)
					(name "CA4_B"
						(effects
							(font
								(size 1.016 1.016)
							)
						)
					)
					(number "156"
						(effects
							(font
								(size 1.016 1.016)
							)
						)
					)
				)
				(pin passive line
					(at 0 -53.34 0)
					(length 3.81)
					(name "CA5_B"
						(effects
							(font
								(size 1.016 1.016)
							)
						)
					)
					(number "155"
						(effects
							(font
								(size 1.016 1.016)
							)
						)
					)
				)
				(pin passive line
					(at 0 -55.88 0)
					(length 3.81)
					(name "CA6_B"
						(effects
							(font
								(size 1.016 1.016)
							)
						)
					)
					(number "152"
						(effects
							(font
								(size 1.016 1.016)
							)
						)
					)
				)
				(pin passive line
					(at 0 -58.42 0)
					(length 3.81)
					(name "CA7_B"
						(effects
							(font
								(size 1.016 1.016)
							)
						)
					)
					(number "151"
						(effects
							(font
								(size 1.016 1.016)
							)
						)
					)
				)
				(pin passive line
					(at 0 -60.96 0)
					(length 3.81)
					(name "CA8_B"
						(effects
							(font
								(size 1.016 1.016)
							)
						)
					)
					(number "150"
						(effects
							(font
								(size 1.016 1.016)
							)
						)
					)
				)
				(pin passive line
					(at 0 -63.5 0)
					(length 3.81)
					(name "CA9_B"
						(effects
							(font
								(size 1.016 1.016)
							)
						)
					)
					(number "149"
						(effects
							(font
								(size 1.016 1.016)
							)
						)
					)
				)
				(pin passive line
					(at 0 -66.04 0)
					(length 3.81)
					(name "CA10_B"
						(effects
							(font
								(size 1.016 1.016)
							)
						)
					)
					(number "146"
						(effects
							(font
								(size 1.016 1.016)
							)
						)
					)
				)
				(pin passive line
					(at 0 -68.58 0)
					(length 3.81)
					(name "CA11_B"
						(effects
							(font
								(size 1.016 1.016)
							)
						)
					)
					(number "145"
						(effects
							(font
								(size 1.016 1.016)
							)
						)
					)
				)
				(pin passive line
					(at 0 -71.12 0)
					(length 3.81)
					(name "CA12_B"
						(effects
							(font
								(size 1.016 1.016)
							)
						)
					)
					(number "144"
						(effects
							(font
								(size 1.016 1.016)
							)
						)
					)
				)
				(pin passive line
					(at 0 -78.74 0)
					(length 3.81)
					(name "DQS4_B_T"
						(effects
							(font
								(size 1.016 1.016)
							)
						)
					)
					(number "171"
						(effects
							(font
								(size 1.016 1.016)
							)
						)
					)
				)
				(pin passive line
					(at 0 -81.28 0)
					(length 3.81)
					(name "DQS4_B_c"
						(effects
							(font
								(size 1.016 1.016)
							)
						)
					)
					(number "169"
						(effects
							(font
								(size 1.016 1.016)
							)
						)
					)
				)
				(pin passive line
					(at 0 -86.36 0)
					(length 3.81)
					(name "CB0_B"
						(effects
							(font
								(size 1.016 1.016)
							)
						)
					)
					(number "168"
						(effects
							(font
								(size 1.016 1.016)
							)
						)
					)
				)
				(pin passive line
					(at 0 -88.9 0)
					(length 3.81)
					(name "CB1_B"
						(effects
							(font
								(size 1.016 1.016)
							)
						)
					)
					(number "172"
						(effects
							(font
								(size 1.016 1.016)
							)
						)
					)
				)
				(pin passive line
					(at 0 -91.44 0)
					(length 3.81)
					(name "CB2_B"
						(effects
							(font
								(size 1.016 1.016)
							)
						)
					)
					(number "176"
						(effects
							(font
								(size 1.016 1.016)
							)
						)
					)
				)
				(pin passive line
					(at 0 -93.98 0)
					(length 3.81)
					(name "CB3_B"
						(effects
							(font
								(size 1.016 1.016)
							)
						)
					)
					(number "175"
						(effects
							(font
								(size 1.016 1.016)
							)
						)
					)
				)
				(pin passive line
					(at 35.56 0 180)
					(length 3.81)
					(name "DQS0_B_t"
						(effects
							(font
								(size 1.016 1.016)
							)
						)
					)
					(number "190"
						(effects
							(font
								(size 1.016 1.016)
							)
						)
					)
				)
				(pin passive line
					(at 35.56 -2.54 180)
					(length 3.81)
					(name "DQS0_B_C"
						(effects
							(font
								(size 1.016 1.016)
							)
						)
					)
					(number "188"
						(effects
							(font
								(size 1.016 1.016)
							)
						)
					)
				)
				(pin passive line
					(at 35.56 -7.62 180)
					(length 3.81)
					(name "DQ0_B"
						(effects
							(font
								(size 1.016 1.016)
							)
						)
					)
					(number "179"
						(effects
							(font
								(size 1.016 1.016)
							)
						)
					)
				)
				(pin passive line
					(at 35.56 -10.16 180)
					(length 3.81)
					(name "DQ1_B"
						(effects
							(font
								(size 1.016 1.016)
							)
						)
					)
					(number "180"
						(effects
							(font
								(size 1.016 1.016)
							)
						)
					)
				)
				(pin passive line
					(at 35.56 -12.7 180)
					(length 3.81)
					(name "DQ2_B"
						(effects
							(font
								(size 1.016 1.016)
							)
						)
					)
					(number "183"
						(effects
							(font
								(size 1.016 1.016)
							)
						)
					)
				)
				(pin passive line
					(at 35.56 -15.24 180)
					(length 3.81)
					(name "DQ3_B"
						(effects
							(font
								(size 1.016 1.016)
							)
						)
					)
					(number "184"
						(effects
							(font
								(size 1.016 1.016)
							)
						)
					)
				)
				(pin passive line
					(at 35.56 -17.78 180)
					(length 3.81)
					(name "DQ4_B"
						(effects
							(font
								(size 1.016 1.016)
							)
						)
					)
					(number "191"
						(effects
							(font
								(size 1.016 1.016)
							)
						)
					)
				)
				(pin passive line
					(at 35.56 -20.32 180)
					(length 3.81)
					(name "DQ5_B"
						(effects
							(font
								(size 1.016 1.016)
							)
						)
					)
					(number "194"
						(effects
							(font
								(size 1.016 1.016)
							)
						)
					)
				)
				(pin passive line
					(at 35.56 -22.86 180)
					(length 3.81)
					(name "DQ6_B"
						(effects
							(font
								(size 1.016 1.016)
							)
						)
					)
					(number "195"
						(effects
							(font
								(size 1.016 1.016)
							)
						)
					)
				)
				(pin passive line
					(at 35.56 -25.4 180)
					(length 3.81)
					(name "DQ7_B"
						(effects
							(font
								(size 1.016 1.016)
							)
						)
					)
					(number "198"
						(effects
							(font
								(size 1.016 1.016)
							)
						)
					)
				)
				(pin passive line
					(at 35.56 -30.48 180)
					(length 3.81)
					(name "DQS1_B_t"
						(effects
							(font
								(size 1.016 1.016)
							)
						)
					)
					(number "209"
						(effects
							(font
								(size 1.016 1.016)
							)
						)
					)
				)
				(pin passive line
					(at 35.56 -33.02 180)
					(length 3.81)
					(name "DQS1_B_C"
						(effects
							(font
								(size 1.016 1.016)
							)
						)
					)
					(number "207"
						(effects
							(font
								(size 1.016 1.016)
							)
						)
					)
				)
				(pin passive line
					(at 35.56 -38.1 180)
					(length 3.81)
					(name "DQ8_B"
						(effects
							(font
								(size 1.016 1.016)
							)
						)
					)
					(number "199"
						(effects
							(font
								(size 1.016 1.016)
							)
						)
					)
				)
				(pin passive line
					(at 35.56 -40.64 180)
					(length 3.81)
					(name "DQ9_B"
						(effects
							(font
								(size 1.016 1.016)
							)
						)
					)
					(number "202"
						(effects
							(font
								(size 1.016 1.016)
							)
						)
					)
				)
				(pin passive line
					(at 35.56 -43.18 180)
					(length 3.81)
					(name "DQ10_B"
						(effects
							(font
								(size 1.016 1.016)
							)
						)
					)
					(number "203"
						(effects
							(font
								(size 1.016 1.016)
							)
						)
					)
				)
				(pin passive line
					(at 35.56 -45.72 180)
					(length 3.81)
					(name "DQ11_B"
						(effects
							(font
								(size 1.016 1.016)
							)
						)
					)
					(number "206"
						(effects
							(font
								(size 1.016 1.016)
							)
						)
					)
				)
				(pin passive line
					(at 35.56 -48.26 180)
					(length 3.81)
					(name "DQ12_B"
						(effects
							(font
								(size 1.016 1.016)
							)
						)
					)
					(number "213"
						(effects
							(font
								(size 1.016 1.016)
							)
						)
					)
				)
				(pin passive line
					(at 35.56 -50.8 180)
					(length 3.81)
					(name "DQ13_B"
						(effects
							(font
								(size 1.016 1.016)
							)
						)
					)
					(number "214"
						(effects
							(font
								(size 1.016 1.016)
							)
						)
					)
				)
				(pin passive line
					(at 35.56 -53.34 180)
					(length 3.81)
					(name "DQ14_B"
						(effects
							(font
								(size 1.016 1.016)
							)
						)
					)
					(number "217"
						(effects
							(font
								(size 1.016 1.016)
							)
						)
					)
				)
				(pin passive line
					(at 35.56 -55.88 180)
					(length 3.81)
					(name "DQ15_B"
						(effects
							(font
								(size 1.016 1.016)
							)
						)
					)
					(number "218"
						(effects
							(font
								(size 1.016 1.016)
							)
						)
					)
				)
				(pin passive line
					(at 35.56 -60.96 180)
					(length 3.81)
					(name "DQS2_B_t"
						(effects
							(font
								(size 1.016 1.016)
							)
						)
					)
					(number "232"
						(effects
							(font
								(size 1.016 1.016)
							)
						)
					)
				)
				(pin passive line
					(at 35.56 -63.5 180)
					(length 3.81)
					(name "DQS2_B_C"
						(effects
							(font
								(size 1.016 1.016)
							)
						)
					)
					(number "230"
						(effects
							(font
								(size 1.016 1.016)
							)
						)
					)
				)
				(pin passive line
					(at 35.56 -68.58 180)
					(length 3.81)
					(name "DQ16_B"
						(effects
							(font
								(size 1.016 1.016)
							)
						)
					)
					(number "221"
						(effects
							(font
								(size 1.016 1.016)
							)
						)
					)
				)
				(pin passive line
					(at 35.56 -71.12 180)
					(length 3.81)
					(name "DQ17_B"
						(effects
							(font
								(size 1.016 1.016)
							)
						)
					)
					(number "222"
						(effects
							(font
								(size 1.016 1.016)
							)
						)
					)
				)
				(pin passive line
					(at 35.56 -73.66 180)
					(length 3.81)
					(name "DQ18_B"
						(effects
							(font
								(size 1.016 1.016)
							)
						)
					)
					(number "225"
						(effects
							(font
								(size 1.016 1.016)
							)
						)
					)
				)
				(pin passive line
					(at 35.56 -76.2 180)
					(length 3.81)
					(name "DQ19_B"
						(effects
							(font
								(size 1.016 1.016)
							)
						)
					)
					(number "226"
						(effects
							(font
								(size 1.016 1.016)
							)
						)
					)
				)
				(pin passive line
					(at 35.56 -78.74 180)
					(length 3.81)
					(name "DQ20_B"
						(effects
							(font
								(size 1.016 1.016)
							)
						)
					)
					(number "233"
						(effects
							(font
								(size 1.016 1.016)
							)
						)
					)
				)
				(pin passive line
					(at 35.56 -81.28 180)
					(length 3.81)
					(name "DQ21_B"
						(effects
							(font
								(size 1.016 1.016)
							)
						)
					)
					(number "236"
						(effects
							(font
								(size 1.016 1.016)
							)
						)
					)
				)
				(pin passive line
					(at 35.56 -83.82 180)
					(length 3.81)
					(name "DQ22_B"
						(effects
							(font
								(size 1.016 1.016)
							)
						)
					)
					(number "237"
						(effects
							(font
								(size 1.016 1.016)
							)
						)
					)
				)
				(pin passive line
					(at 35.56 -86.36 180)
					(length 3.81)
					(name "DQ23_B"
						(effects
							(font
								(size 1.016 1.016)
							)
						)
					)
					(number "240"
						(effects
							(font
								(size 1.016 1.016)
							)
						)
					)
				)
				(pin passive line
					(at 35.56 -91.44 180)
					(length 3.81)
					(name "DQS3_B_t"
						(effects
							(font
								(size 1.016 1.016)
							)
						)
					)
					(number "251"
						(effects
							(font
								(size 1.016 1.016)
							)
						)
					)
				)
				(pin passive line
					(at 35.56 -93.98 180)
					(length 3.81)
					(name "DQS3_B_c"
						(effects
							(font
								(size 1.016 1.016)
							)
						)
					)
					(number "249"
						(effects
							(font
								(size 1.016 1.016)
							)
						)
					)
				)
				(pin passive line
					(at 35.56 -99.06 180)
					(length 3.81)
					(name "DQ24_B"
						(effects
							(font
								(size 1.016 1.016)
							)
						)
					)
					(number "241"
						(effects
							(font
								(size 1.016 1.016)
							)
						)
					)
				)
				(pin passive line
					(at 35.56 -101.6 180)
					(length 3.81)
					(name "DQ25_B"
						(effects
							(font
								(size 1.016 1.016)
							)
						)
					)
					(number "244"
						(effects
							(font
								(size 1.016 1.016)
							)
						)
					)
				)
				(pin passive line
					(at 35.56 -104.14 180)
					(length 3.81)
					(name "DQ26_B"
						(effects
							(font
								(size 1.016 1.016)
							)
						)
					)
					(number "245"
						(effects
							(font
								(size 1.016 1.016)
							)
						)
					)
				)
				(pin passive line
					(at 35.56 -106.68 180)
					(length 3.81)
					(name "DQ27_B"
						(effects
							(font
								(size 1.016 1.016)
							)
						)
					)
					(number "248"
						(effects
							(font
								(size 1.016 1.016)
							)
						)
					)
				)
				(pin passive line
					(at 35.56 -109.22 180)
					(length 3.81)
					(name "DQ28_B"
						(effects
							(font
								(size 1.016 1.016)
							)
						)
					)
					(number "255"
						(effects
							(font
								(size 1.016 1.016)
							)
						)
					)
				)
				(pin passive line
					(at 35.56 -111.76 180)
					(length 3.81)
					(name "DQ29_B"
						(effects
							(font
								(size 1.016 1.016)
							)
						)
					)
					(number "256"
						(effects
							(font
								(size 1.016 1.016)
							)
						)
					)
				)
				(pin passive line
					(at 35.56 -114.3 180)
					(length 3.81)
					(name "DQ30_B"
						(effects
							(font
								(size 1.016 1.016)
							)
						)
					)
					(number "259"
						(effects
							(font
								(size 1.016 1.016)
							)
						)
					)
				)
				(pin passive line
					(at 35.56 -116.84 180)
					(length 3.81)
					(name "DQ31_B"
						(effects
							(font
								(size 1.016 1.016)
							)
						)
					)
					(number "260"
						(effects
							(font
								(size 1.016 1.016)
							)
						)
					)
				)
			)
			(symbol "Edge_Conn_Bus_DDR5_SODIMM_1xDetectPin_3_1"
				(rectangle
					(start 3.81 2.54)
					(end 31.75 -119.38)
					(stroke
						(width 0)
						(type default)
					)
					(fill
						(type background)
					)
				)
				(polyline
					(pts
						(xy 10.16 -76.2) (xy 13.97 -76.2) (xy 13.97 -96.52) (xy 10.16 -96.52)
					)
					(stroke
						(width 0)
						(type default)
					)
					(fill
						(type none)
					)
				)
				(polyline
					(pts
						(xy 22.86 0) (xy 22.86 -25.4)
					)
					(stroke
						(width 0)
						(type default)
					)
					(fill
						(type none)
					)
				)
				(polyline
					(pts
						(xy 22.86 -30.48) (xy 22.86 -55.88)
					)
					(stroke
						(width 0)
						(type default)
					)
					(fill
						(type none)
					)
				)
				(polyline
					(pts
						(xy 22.86 -60.96) (xy 22.86 -86.36)
					)
					(stroke
						(width 0)
						(type default)
					)
					(fill
						(type none)
					)
				)
				(polyline
					(pts
						(xy 22.86 -91.44) (xy 22.86 -116.84)
					)
					(stroke
						(width 0)
						(type default)
					)
					(fill
						(type none)
					)
				)
				(text "ECC"
					(at 12.7 -86.36 900)
					(effects
						(font
							(size 1.27 1.27)
						)
					)
				)
			)
		)
)
